# Altium SchDoc records: Antenna_Supervisor.SchDoc
|HEADER=Protel for Windows - Schematic Capture Binary File Version 5.0|Weight=1318|MinorVersion=4
|RECORD=31|FontIdCount=16|Size1=10|FontName1=Times New Roman|Size2=10|Underline2=T|FontName2=Times New Roman|Size3=14|FontName3=Arial Narrow|Size4=12|FontName4=Arial|Size5=8|FontName5=Arial|Size6=10|FontName6=Arial|Size7=14|FontName7=Arial|Size8=9|FontName8=Arial|Size9=9|FontName9=Arial Narrow|Size10=22|FontName10=Arial Narrow|Size11=6|Rotation11=90|FontName11=Arial|Size12=6|FontName12=Arial|Size13=9|Rotation13=90|FontName13=Arial|Size14=24|FontName14=Arial|Size15=30|FontName15=Times New Roman|Size16=14|FontName16=Times New Roman|UseMBCS=T|IsBOC=T|HotSpotGridOn=T|HotSpotGridSize=4|SheetStyle=5|SystemFont=6|BorderOn=T|TitleBlockOn=T|SheetNumberSpaceSize=12|AreaColor=16317695|SnapGridOn=T|SnapGridSize=10|VisibleGridOn=T|VisibleGridSize=10|CustomX=1700|CustomY=1100|CustomXZones=8|CustomYZones=6|CustomMarginWidth=20|Display_Unit=0|ReferenceZoneStyle=1
|RECORD=39|IsNotAccesible=T|OwnerPartId=-1|FileName=C:\Users\<user>\Documents\Altium\AD22\Templates\ANSI B Landscape.SchDot
|RECORD=4|OwnerIndex=1|OwnerPartId=-1|Location.X=1345|Location.Y=1068|FontID=9|Text=REVISION
|RECORD=4|OwnerIndex=1|IndexInSheet=1|OwnerPartId=-1|Location.X=1460|Location.Y=1068|FontID=9|Text=DESCRIPTION
|RECORD=4|OwnerIndex=1|IndexInSheet=2|OwnerPartId=-1|Location.X=1592|Location.Y=1068|FontID=9|Text=DATE
|RECORD=4|OwnerIndex=1|IndexInSheet=3|OwnerPartId=-1|Location.X=1633|Location.Y=1068|FontID=9|Text=APPROVED
|RECORD=6|OwnerIndex=1|IndexInSheet=4|OwnerPartId=-1|LocationCount=3|X1=1340|Y1=1080|X2=1340|Y2=1065|X3=1680|Y3=1065
|RECORD=6|OwnerIndex=1|IndexInSheet=5|OwnerPartId=-1|LocationCount=2|X1=1380|Y1=1080|X2=1380|Y2=1065
|RECORD=6|OwnerIndex=1|IndexInSheet=6|OwnerPartId=-1|LocationCount=2|X1=1620|Y1=1080|X2=1620|Y2=1065
|RECORD=6|OwnerIndex=1|IndexInSheet=7|OwnerPartId=-1|LocationCount=2|X1=1580|Y1=1080|X2=1580|Y2=1065
|RECORD=6|OwnerIndex=1|IndexInSheet=8|OwnerPartId=-1|LocationCount=3|X1=1340|Y1=1070|X2=1340|Y2=1050|X3=1680|Y3=1050
|RECORD=6|OwnerIndex=1|IndexInSheet=9|OwnerPartId=-1|LocationCount=2|X1=1380|Y1=1065|X2=1380|Y2=1050
|RECORD=6|OwnerIndex=1|IndexInSheet=10|OwnerPartId=-1|LocationCount=2|X1=1580|Y1=1065|X2=1580|Y2=1050
|RECORD=6|OwnerIndex=1|IndexInSheet=11|OwnerPartId=-1|LocationCount=2|X1=1620|Y1=1065|X2=1620|Y2=1050
|RECORD=6|OwnerIndex=1|IndexInSheet=12|OwnerPartId=-1|LineWidth=1|LocationCount=2|X1=1695|Y1=184|X2=1700|Y2=184
|RECORD=4|OwnerIndex=1|IndexInSheet=13|OwnerPartId=-1|Location.X=1689|Location.Y=189|Orientation=3|FontID=11|Text=REV.
|RECORD=4|OwnerIndex=1|IndexInSheet=14|OwnerPartId=-1|Location.X=1689|Location.Y=174|Orientation=3|FontID=11|Text=SHT.
|RECORD=4|OwnerIndex=1|IndexInSheet=15|OwnerPartId=-1|Location.X=1695|Location.Y=259|Orientation=3|Justification=6|FontID=11|Text=DWG. NO.|IsMirrored=T
|RECORD=4|OwnerIndex=1|IndexInSheet=16|OwnerPartId=-1|Location.X=1680|Location.Y=258|Orientation=3|FontID=13|Text==DOC_NO_SCH_DWG
|RECORD=4|OwnerIndex=1|IndexInSheet=17|OwnerPartId=-1|Location.X=1680|Location.Y=182|Orientation=3|Justification=1|FontID=13|Text==ItemRevision
|RECORD=4|OwnerIndex=1|IndexInSheet=18|OwnerPartId=-1|Location.X=1680|Location.Y=169|Orientation=3|Justification=1|FontID=13|Text==SheetNumber
|RECORD=6|OwnerIndex=1|IndexInSheet=19|OwnerPartId=-1|LineWidth=1|LocationCount=3|X1=1695|Y1=160|X2=1695|Y2=260|X3=1680|Y3=260
|RECORD=6|OwnerIndex=1|IndexInSheet=20|OwnerPartId=-1|LocationCount=2|X1=1695|Y1=175|X2=1680|Y2=175
|RECORD=6|OwnerIndex=1|IndexInSheet=21|OwnerPartId=-1|LocationCount=2|X1=1695|Y1=190|X2=1680|Y2=190
|RECORD=6|OwnerIndex=1|IndexInSheet=22|OwnerPartId=-1|LineWidth=1|LocationCount=2|X1=1695|Y1=160|X2=1680|Y2=160
|RECORD=4|OwnerIndex=1|IndexInSheet=23|OwnerPartId=-1|Location.X=1312|Location.Y=1080|FontID=12|Text=REV.
|RECORD=4|OwnerIndex=1|IndexInSheet=24|OwnerPartId=-1|Location.X=1327|Location.Y=1080|FontID=12|Text=SHT.
|RECORD=4|OwnerIndex=1|IndexInSheet=25|OwnerPartId=-1|Location.X=1283|Location.Y=1086|Justification=6|FontID=12|Text=DWG. NO.|IsMirrored=T
|RECORD=4|OwnerIndex=1|IndexInSheet=26|OwnerPartId=-1|Location.X=1247|Location.Y=1085|FontID=8|Text==DOC_NO_SCH_DWG
|RECORD=4|OwnerIndex=1|IndexInSheet=27|OwnerPartId=-1|Location.X=1317|Location.Y=1085|Justification=1|FontID=8|Text==ItemRevision
|RECORD=4|OwnerIndex=1|IndexInSheet=28|OwnerPartId=-1|Location.X=1332|Location.Y=1085|Justification=1|FontID=8|Text==SheetNumber
|RECORD=6|OwnerIndex=1|IndexInSheet=29|OwnerPartId=-1|LineWidth=1|LocationCount=3|X1=1340|Y1=1095|X2=1240|Y2=1095|X3=1240|Y3=1080
|RECORD=6|OwnerIndex=1|IndexInSheet=30|OwnerPartId=-1|LocationCount=2|X1=1325|Y1=1095|X2=1325|Y2=1080
|RECORD=6|OwnerIndex=1|IndexInSheet=31|OwnerPartId=-1|LocationCount=2|X1=1310|Y1=1095|X2=1310|Y2=1080
|RECORD=6|OwnerIndex=1|IndexInSheet=32|OwnerPartId=-1|LineWidth=1|LocationCount=2|X1=1340|Y1=1095|X2=1340|Y2=1080
|RECORD=7|OwnerIndex=1|IndexInSheet=33|OwnerPartId=-1|IsSolid=T|LocationCount=3|X1=850|Y1=1080|X2=855|Y2=1090|X3=845|Y3=1090
|RECORD=7|OwnerIndex=1|IndexInSheet=34|OwnerPartId=-1|IsSolid=T|LocationCount=3|X1=850|Y1=20|X2=845|Y2=10|X3=855|Y3=10
|RECORD=7|OwnerIndex=1|IndexInSheet=35|OwnerPartId=-1|IsSolid=T|LocationCount=3|X1=1680|Y1=550|X2=1690|Y2=545|X3=1690|Y3=555
|RECORD=28|OwnerIndex=1|IndexInSheet=36|OwnerPartId=-1|UnionIndex=1|Location.X=25|Location.Y=1033|Corner.X=298|Corner.Y=1075|AreaColor=16777215|FontID=6|Alignment=1|WordWrap=T|Text=THIS DOCUMENT AND THE DATA DISCLOSED HEREIN OR HEREWITH IS THE PROPERTY OF ALTIUM LIMITED AND MAY BE FREELY DISTRIBUTED IN WHOLE. NO RIGHTS ARE RESERVED OR EXPRESS OR IMPLIED WARANTEE GIVEN.|TextMargin_Frac=5
|RECORD=6|OwnerIndex=1|IndexInSheet=37|OwnerPartId=-1|UnionIndex=1|LineWidth=1|LocationCount=5|X1=300|Y1=1080|X2=20|Y2=1080|X3=20|Y3=1032|X4=300|Y4=1032|X5=300|Y5=1080
|RECORD=13|OwnerIndex=1|IndexInSheet=38|OwnerPartId=-1|Location.Y=1100|Corner.X=1699|Corner.X_Frac=83312|Corner.Y=1100|LineWidth=1
|RECORD=13|OwnerIndex=1|IndexInSheet=39|OwnerPartId=-1|Location.X=1699|Location.X_Frac=83312|Location.Y=1100|Corner.X=1699|Corner.X_Frac=83312|Corner.Y_Frac=16696|LineWidth=1
|RECORD=13|OwnerIndex=1|IndexInSheet=40|OwnerPartId=-1|Location.X=1699|Location.X_Frac=83312|Location.Y_Frac=16696|Corner.Y_Frac=16696|LineWidth=1
|RECORD=13|OwnerIndex=1|IndexInSheet=41|OwnerPartId=-1|Location.Y_Frac=16696|Corner.Y=1100|LineWidth=1
|RECORD=13|OwnerIndex=1|IndexInSheet=42|OwnerPartId=-1|Location.X=20|Location.X_Frac=12|Location.Y=1079|Location.Y_Frac=99791|Corner.X=1679|Corner.X_Frac=83296|Corner.Y=1079|Corner.Y_Frac=99791|LineWidth=1
|RECORD=13|OwnerIndex=1|IndexInSheet=43|OwnerPartId=-1|Location.X=1679|Location.X_Frac=83296|Location.Y=1079|Location.Y_Frac=99791|Corner.X=1679|Corner.X_Frac=83296|Corner.Y=20|Corner.Y_Frac=16904|LineWidth=1
|RECORD=13|OwnerIndex=1|IndexInSheet=44|OwnerPartId=-1|Location.X=1679|Location.X_Frac=83296|Location.Y=20|Location.Y_Frac=16904|Corner.X=20|Corner.X_Frac=12|Corner.Y=20|Corner.Y_Frac=16904|LineWidth=1
|RECORD=13|OwnerIndex=1|IndexInSheet=45|OwnerPartId=-1|Location.X=20|Location.X_Frac=12|Location.Y=20|Location.Y_Frac=16904|Corner.X=20|Corner.X_Frac=12|Corner.Y=1079|Corner.Y_Frac=99791|LineWidth=1
|RECORD=13|OwnerIndex=1|IndexInSheet=46|OwnerPartId=-1|Location.X=1487|Location.X_Frac=50000|Location.Y=20|Corner.X=1487|Corner.X_Frac=50000|LineWidth=1
|RECORD=13|OwnerIndex=1|IndexInSheet=47|OwnerPartId=-1|Location.X=1487|Location.X_Frac=50000|Location.Y=1080|Corner.X=1487|Corner.X_Frac=50000|Corner.Y=1100|LineWidth=1
|RECORD=13|OwnerIndex=1|IndexInSheet=48|OwnerPartId=-1|Location.X=1275|Location.Y=20|Corner.X=1275|LineWidth=1
|RECORD=13|OwnerIndex=1|IndexInSheet=49|OwnerPartId=-1|Location.X=1275|Location.Y=1095|Corner.X=1275|Corner.Y=1100|LineWidth=1
|RECORD=13|OwnerIndex=1|IndexInSheet=50|OwnerPartId=-1|Location.X=1062|Location.X_Frac=50000|Location.Y=20|Corner.X=1062|Corner.X_Frac=50000|LineWidth=1
|RECORD=13|OwnerIndex=1|IndexInSheet=51|OwnerPartId=-1|Location.X=1062|Location.X_Frac=50000|Location.Y=1080|Corner.X=1062|Corner.X_Frac=50000|Corner.Y=1100|LineWidth=1
|RECORD=13|OwnerIndex=1|IndexInSheet=52|OwnerPartId=-1|Location.X=850|Location.Y=20|Corner.X=850|LineWidth=1
|RECORD=13|OwnerIndex=1|IndexInSheet=53|OwnerPartId=-1|Location.X=850|Location.Y=1080|Corner.X=850|Corner.Y=1100|LineWidth=1
|RECORD=13|OwnerIndex=1|IndexInSheet=54|OwnerPartId=-1|Location.X=637|Location.X_Frac=50000|Location.Y=20|Corner.X=637|Corner.X_Frac=50000|LineWidth=1
|RECORD=13|OwnerIndex=1|IndexInSheet=55|OwnerPartId=-1|Location.X=637|Location.X_Frac=50000|Location.Y=1080|Corner.X=637|Corner.X_Frac=50000|Corner.Y=1100|LineWidth=1
|RECORD=13|OwnerIndex=1|IndexInSheet=56|OwnerPartId=-1|Location.X=425|Location.Y=20|Corner.X=425|LineWidth=1
|RECORD=13|OwnerIndex=1|IndexInSheet=57|OwnerPartId=-1|Location.X=425|Location.Y=1080|Corner.X=425|Corner.Y=1100|LineWidth=1
|RECORD=13|OwnerIndex=1|IndexInSheet=58|OwnerPartId=-1|Location.X=212|Location.X_Frac=50000|Location.Y=20|Corner.X=212|Corner.X_Frac=50000|LineWidth=1
|RECORD=13|OwnerIndex=1|IndexInSheet=59|OwnerPartId=-1|Location.X=212|Location.X_Frac=50000|Location.Y=1080|Corner.X=212|Corner.X_Frac=50000|Corner.Y=1100|LineWidth=1
|RECORD=13|OwnerIndex=1|IndexInSheet=60|OwnerPartId=-1|Location.X=20|Location.Y=916|Location.Y_Frac=66664|Corner.Y=916|Corner.Y_Frac=66664|LineWidth=1
|RECORD=13|OwnerIndex=1|IndexInSheet=61|OwnerPartId=-1|Location.X=1680|Location.Y=916|Location.Y_Frac=66664|Corner.X=1700|Corner.Y=916|Corner.Y_Frac=66664|LineWidth=1
|RECORD=13|OwnerIndex=1|IndexInSheet=62|OwnerPartId=-1|Location.X=20|Location.Y=733|Location.Y_Frac=33328|Corner.Y=733|Corner.Y_Frac=33328|LineWidth=1
|RECORD=13|OwnerIndex=1|IndexInSheet=63|OwnerPartId=-1|Location.X=1680|Location.Y=733|Location.Y_Frac=33328|Corner.X=1700|Corner.Y=733|Corner.Y_Frac=33328|LineWidth=1
|RECORD=13|OwnerIndex=1|IndexInSheet=64|OwnerPartId=-1|Location.X=20|Location.Y=550|Corner.Y=550|LineWidth=1
|RECORD=13|OwnerIndex=1|IndexInSheet=65|OwnerPartId=-1|Location.X=1680|Location.Y=550|Corner.X=1700|Corner.Y=550|LineWidth=1
|RECORD=13|OwnerIndex=1|IndexInSheet=66|OwnerPartId=-1|Location.X=20|Location.Y=366|Location.Y_Frac=66664|Corner.Y=366|Corner.Y_Frac=66664|LineWidth=1
|RECORD=13|OwnerIndex=1|IndexInSheet=67|OwnerPartId=-1|Location.X=1680|Location.Y=366|Location.Y_Frac=66664|Corner.X=1700|Corner.Y=366|Corner.Y_Frac=66664|LineWidth=1
|RECORD=13|OwnerIndex=1|IndexInSheet=68|OwnerPartId=-1|Location.X=20|Location.Y=183|Location.Y_Frac=33330|Corner.Y=183|Corner.Y_Frac=33330|LineWidth=1
|RECORD=7|OwnerIndex=1|IndexInSheet=69|OwnerPartId=-1|IsSolid=T|LocationCount=3|X1=20|Y1=550|X2=10|Y2=545|X3=10|Y3=555
|RECORD=4|OwnerIndex=1|IndexInSheet=70|OwnerPartId=-1|Location.X=1348|Location.Y=71|FontID=14|Text==title
|RECORD=4|OwnerIndex=1|IndexInSheet=71|OwnerPartId=-1|Location.X=1450|Location.Y=40|FontID=3|Text==DOC_NO_SCH_DWG
|RECORD=6|OwnerIndex=1|IndexInSheet=72|OwnerPartId=-1|LocationCount=2|X1=1405|Y1=65|X2=1405|Y2=35
|RECORD=6|OwnerIndex=1|IndexInSheet=73|OwnerPartId=-1|LocationCount=2|X1=1680|Y1=35|X2=1320|Y2=35
|RECORD=6|OwnerIndex=1|IndexInSheet=74|OwnerPartId=-1|LocationCount=2|X1=1650|Y1=65|X2=1650|Y2=35
|RECORD=4|OwnerIndex=1|IndexInSheet=75|OwnerPartId=-1|Location.X=1330|Location.Y=35|FontID=10|Text=B
|RECORD=4|OwnerIndex=1|IndexInSheet=76|OwnerPartId=-1|Location.X=1428|Location.Y=20|FontID=4|Text==DocumentName
|RECORD=4|OwnerIndex=1|IndexInSheet=77|OwnerPartId=-1|Location.X=1615|Location.Y=20|FontID=4|Text==SheetNumber
|RECORD=4|OwnerIndex=1|IndexInSheet=78|OwnerPartId=-1|Location.X=1655|Location.Y=20|FontID=4|Text==SheetTotal
|RECORD=4|OwnerIndex=1|IndexInSheet=79|OwnerPartId=-1|Location.X=1323|Location.Y=100|Justification=3|FontID=5|Text=TITLE
|RECORD=4|OwnerIndex=1|IndexInSheet=80|OwnerPartId=-1|Location.X=1328|Location.Y=60|Justification=3|FontID=5|Text=SIZE
|RECORD=4|OwnerIndex=1|IndexInSheet=81|OwnerPartId=-1|Location.X=1407|Location.Y=60|Justification=3|FontID=5|Text=DWG NO.
|RECORD=4|OwnerIndex=1|IndexInSheet=82|OwnerPartId=-1|Location.X=1387|Location.Y=30|Justification=3|FontID=5|Text=FILE NAME
|RECORD=4|OwnerIndex=1|IndexInSheet=83|OwnerPartId=-1|Location.X=1582|Location.Y=30|Justification=3|FontID=5|Text=SHEET
|RECORD=4|OwnerIndex=1|IndexInSheet=84|OwnerPartId=-1|Location.X=1640|Location.Y=30|Justification=3|FontID=5|Text=OF
|RECORD=4|OwnerIndex=1|IndexInSheet=85|OwnerPartId=-1|Location.X=1657|Location.Y=60|Justification=3|FontID=5|Text=REV
|RECORD=6|OwnerIndex=1|IndexInSheet=86|OwnerPartId=-1|LocationCount=2|X1=1385|Y1=35|X2=1385|Y2=20
|RECORD=4|OwnerIndex=1|IndexInSheet=87|OwnerPartId=-1|Location.X=1322|Location.Y=30|Justification=3|FontID=5|Text=SCALE:
|RECORD=4|OwnerIndex=1|IndexInSheet=88|OwnerPartId=-1|Location.X=1349|Location.Y=20|FontID=4|Text==SCH_SCALE
|RECORD=6|OwnerIndex=1|IndexInSheet=89|OwnerPartId=-1|LocationCount=2|X1=1580|Y1=35|X2=1580|Y2=20
|RECORD=4|OwnerIndex=1|IndexInSheet=90|OwnerPartId=-1|Location.X=1355|Location.Y=40|FontID=7|Text==CAGE_CODE
|RECORD=4|OwnerIndex=1|IndexInSheet=91|OwnerPartId=-1|Location.X=1352|Location.Y=56|FontID=5|Text=CAGE CODE
|RECORD=6|OwnerIndex=1|IndexInSheet=92|OwnerPartId=-1|LocationCount=2|X1=1350|Y1=65|X2=1350|Y2=35
|RECORD=6|OwnerIndex=1|IndexInSheet=93|OwnerPartId=-1|LineWidth=1|LocationCount=2|X1=1680|Y1=120|X2=1320|Y2=120
|RECORD=6|OwnerIndex=1|IndexInSheet=94|OwnerPartId=-1|LineWidth=1|LocationCount=2|X1=1680|Y1=160|X2=1320|Y2=160
|RECORD=4|OwnerIndex=1|IndexInSheet=95|OwnerPartId=-1|Location.X=1323|Location.Y=150|FontID=5|Text=PROJECT
|RECORD=6|OwnerIndex=1|IndexInSheet=96|OwnerPartId=-1|LocationCount=2|X1=1390|Y1=160|X2=1390|Y2=120
|RECORD=4|OwnerIndex=1|IndexInSheet=97|OwnerPartId=-1|Location.X=1325|Location.Y=130|FontID=7|Text==Project
|RECORD=4|OwnerIndex=1|IndexInSheet=98|OwnerPartId=-1|Location.X=1613|Location.Y=129|Justification=2|FontID=8|Text==Address3|IsMirrored=T
|RECORD=4|OwnerIndex=1|IndexInSheet=99|OwnerPartId=-1|Location.X=1614|Location.Y=120|Justification=2|FontID=8|Text==Address4|IsMirrored=T
|RECORD=4|OwnerIndex=1|IndexInSheet=100|OwnerPartId=-1|Location.X=1614|Location.Y=150|Justification=2|FontID=8|Text==Address1|IsMirrored=T
|RECORD=4|OwnerIndex=1|IndexInSheet=101|OwnerPartId=-1|Location.X=1614|Location.Y=144|Justification=5|FontID=8|Text==Address2|IsMirrored=T
|RECORD=6|OwnerIndex=1|IndexInSheet=102|OwnerPartId=1|LineWidth=1|LocationCount=2|X1=1320|Y1=65|X2=1320|Y2=35
|RECORD=6|OwnerIndex=1|IndexInSheet=103|OwnerPartId=1|LineWidth=1|LocationCount=2|X1=1320|Y1=35|X2=1320|Y2=20
|RECORD=6|OwnerIndex=1|IndexInSheet=104|OwnerPartId=1|LineWidth=1|LocationCount=2|X1=1320|Y1=65|X2=1320|Y2=120
|RECORD=6|OwnerIndex=1|IndexInSheet=105|OwnerPartId=1|LineWidth=1|LocationCount=2|X1=1320|Y1=120|X2=1320|Y2=160
|RECORD=6|OwnerIndex=1|IndexInSheet=106|OwnerPartId=1|LineWidth=1|LocationCount=3|X1=1320|Y1=160|X2=1180|Y2=160|X3=1180|Y3=20
|RECORD=4|OwnerIndex=1|IndexInSheet=107|OwnerPartId=1|Location.X=1212|Location.Y=145|FontID=5|Text=APPROVALS
|RECORD=4|OwnerIndex=1|IndexInSheet=108|OwnerPartId=1|Location.X=1290|Location.Y=145|FontID=5|Text=DATE
|RECORD=4|OwnerIndex=1|IndexInSheet=109|OwnerPartId=1|Location.X=1182|Location.Y=131|FontID=5|Text=ENG:
|RECORD=4|OwnerIndex=1|IndexInSheet=110|OwnerPartId=1|Location.X=1182|Location.Y=116|FontID=5|Text=DSN:
|RECORD=6|OwnerIndex=1|IndexInSheet=111|OwnerPartId=1|LocationCount=2|X1=1180|Y1=125|X2=1320|Y2=125
|RECORD=6|OwnerIndex=1|IndexInSheet=112|OwnerPartId=1|LocationCount=2|X1=1180|Y1=140|X2=1320|Y2=140
|RECORD=6|OwnerIndex=1|IndexInSheet=113|OwnerPartId=1|LocationCount=2|X1=1280|Y1=160|X2=1280|Y2=95
|RECORD=4|OwnerIndex=1|IndexInSheet=114|OwnerPartId=1|Location.X=1210|Location.Y=125|FontID=5|Text==Engineer
|RECORD=4|OwnerIndex=1|IndexInSheet=115|OwnerPartId=1|Location.X=1210|Location.Y=110|FontID=5|Text==DrawnBy
|RECORD=4|OwnerIndex=1|IndexInSheet=116|OwnerPartId=1|Location.X=1285|Location.Y=125|FontID=5|Text==ENG_APP_DATE
|RECORD=4|OwnerIndex=1|IndexInSheet=117|OwnerPartId=1|Location.X=1285|Location.Y=110|FontID=5|Text==DSN_APP_DATE
|RECORD=6|OwnerIndex=1|IndexInSheet=118|OwnerPartId=1|LineWidth=1|LocationCount=2|X1=1180|Y1=95|X2=1320|Y2=95
|RECORD=6|OwnerIndex=1|IndexInSheet=119|OwnerPartId=1|LocationCount=2|X1=1180|Y1=110|X2=1320|Y2=110
|RECORD=4|OwnerIndex=1|IndexInSheet=120|OwnerPartId=1|Location.X=1182|Location.Y=101|FontID=5|Text=CHK:
|RECORD=4|OwnerIndex=1|IndexInSheet=121|OwnerPartId=1|Location.X=1285|Location.Y=95|FontID=5|Text==CHK_APP_DATE
|RECORD=6|OwnerIndex=1|IndexInSheet=122|OwnerPartId=1|LocationCount=2|X1=1180|Y1=65|X2=1320|Y2=65
|RECORD=6|OwnerIndex=1|IndexInSheet=123|OwnerPartId=1|LocationCount=2|X1=1180|Y1=80|X2=1320|Y2=80
|RECORD=6|OwnerIndex=1|IndexInSheet=124|OwnerPartId=1|LocationCount=2|X1=1180|Y1=35|X2=1320|Y2=35
|RECORD=6|OwnerIndex=1|IndexInSheet=125|OwnerPartId=1|LocationCount=2|X1=1180|Y1=50|X2=1320|Y2=50
|RECORD=4|OwnerIndex=1|IndexInSheet=126|OwnerPartId=-1|Location.X=1204|Location.Y=82|FontID=5|Text=REFERENCE DOCUMENTS
|RECORD=4|OwnerIndex=1|IndexInSheet=127|OwnerPartId=1|Location.X=1182|Location.Y=71|FontID=5|Text=BOM:
|RECORD=4|OwnerIndex=1|IndexInSheet=128|OwnerPartId=1|Location.X=1183|Location.Y=56|FontID=5|Text=ASSY DWG:
|RECORD=4|OwnerIndex=1|IndexInSheet=129|OwnerPartId=1|Location.X=1182|Location.Y=41|FontID=5|Text=FAB DWG:
|RECORD=4|OwnerIndex=1|IndexInSheet=130|OwnerPartId=1|Location.X=1182|Location.Y=26|FontID=5|Text=PCB DWG:
|RECORD=4|OwnerIndex=1|IndexInSheet=131|OwnerPartId=-1|Location.X=1228|Location.Y=22|FontID=6|Text==PCB_DWG_NO
|RECORD=4|OwnerIndex=1|IndexInSheet=132|OwnerPartId=-1|Location.X=1228|Location.Y=37|FontID=6|Text==DOC_NO_FAB_DWG
|RECORD=4|OwnerIndex=1|IndexInSheet=133|OwnerPartId=-1|Location.X=1228|Location.Y=52|FontID=6|Text==DOC_NO_ASSY_DWG
|RECORD=4|OwnerIndex=1|IndexInSheet=134|OwnerPartId=-1|Location.X=1228|Location.Y=68|FontID=6|Text==DOC_NO_BOM
|RECORD=4|OwnerIndex=1|IndexInSheet=135|OwnerPartId=1|Location.X=1210|Location.Y=96|FontID=5|Text==CheckedBy
|RECORD=4|OwnerIndex=1|IndexInSheet=136|OwnerPartId=-1|Location.X=1591|Location.Y=104|FontID=4|Text==Item
|RECORD=6|OwnerIndex=1|IndexInSheet=137|OwnerPartId=-1|LineWidth=1|LocationCount=2|X1=1320|Y1=105|X2=1680|Y2=105
|RECORD=4|OwnerIndex=1|IndexInSheet=138|OwnerPartId=-1|Location.X=1322|Location.Y=115|Justification=3|FontID=5|Text=PROJECT REVISION:
|RECORD=4|OwnerIndex=1|IndexInSheet=139|OwnerPartId=-1|Location.X=1542|Location.Y=116|Justification=3|FontID=5|Text=DESIGN ITEM:
|RECORD=4|OwnerIndex=1|IndexInSheet=140|OwnerPartId=-1|Location.X=1432|Location.Y=116|Justification=3|FontID=5|Text=DOCUMENT REVISION:
|RECORD=6|OwnerIndex=1|IndexInSheet=141|OwnerPartId=-1|LocationCount=2|X1=1430|Y1=120|X2=1430|Y2=105
|RECORD=6|OwnerIndex=1|IndexInSheet=142|OwnerPartId=-1|LocationCount=2|X1=1541|Y1=120|X2=1541|Y2=105
|RECORD=4|OwnerIndex=1|IndexInSheet=143|OwnerPartId=-1|Location.X=1392|Location.Y=104|FontID=4|Text==VersionControl_ProjFolderRevNumber
|RECORD=4|OwnerIndex=1|IndexInSheet=144|OwnerPartId=-1|Location.X=1511|Location.Y=104|FontID=4|Text==VersionControl_RevNumber
|RECORD=6|OwnerIndex=1|IndexInSheet=145|OwnerPartId=-1|LineWidth=1|LocationCount=2|X1=1320|Y1=65|X2=1680|Y2=65
|RECORD=4|OwnerIndex=1|IndexInSheet=146|OwnerPartId=-1|Location.X=1662|Location.Y=41|FontID=4|Text==ItemRevision
|RECORD=30|OwnerIndex=1|IndexInSheet=147|OwnerPartId=-1|Location.X=1398|Location.Y=123|Corner.X=1558|Corner.X_Frac=41666|Corner.Y=158|KeepAspect=T|EmbedImage=T|FileName=Z:\Altium Project Template\Altium Logo\Altm black.jpg
|RECORD=1|LibReference=Transistor_MOS-P-CH_3pins_1G_1S_1D_DIO|ComponentDescription=MOSFET, P-CH, 8VDS, 3.7A ID, 0.052 OHM RDS(ON)@4.5VGS/3.5A, SOT-23-3|PartCount=2|DisplayModeCount=1|IndexInSheet=1|OwnerPartId=-1|Location.X=480|Location.Y=600|IsMirrored=T|Orientation=3|CurrentPartId=1|LibraryPath=*|SourceLibraryName=RL Research Altium Server|TargetFileName=*|AreaColor=11599871|Color=128|PartIDLocked=T|DesignItemId=XQR-CMP-00012-1|AllPinCount=3
|RECORD=8|OwnerIndex=150|IsNotAccesible=T|OwnerPartId=1|Location.X=526|Location.Y=555|Radius=22|SecondaryRadius=22|LineWidth=1|Color=16711680|AreaColor=16777215|IsSolid=T|Transparent=T
|RECORD=2|OwnerIndex=150|OwnerPartId=1|FormalType=1|Electrical=4|PinConglomerate=48|PinLength=30|Location.X=540|Location.Y=550|Name=S|Designator=2|PinPropagationDelay=0.000000E+000
|RECORD=2|OwnerIndex=150|OwnerPartId=1|FormalType=1|Electrical=4|PinConglomerate=49|PinLength=30|Location.X=530|Location.Y=570|Name=G|Designator=1|PinPropagationDelay=0.000000E+000
|RECORD=2|OwnerIndex=150|OwnerPartId=1|FormalType=1|Electrical=4|PinConglomerate=50|PinLength=30|Location.X=510|Location.Y=550|Name=D|Designator=3|PinPropagationDelay=0.000000E+000
|RECORD=6|OwnerIndex=150|IsNotAccesible=T|IndexInSheet=4|OwnerPartId=1|LineWidth=1|Color=16711680|LocationCount=2|X1=530|Y1=570|X2=530|Y2=563
|RECORD=6|OwnerIndex=150|IsNotAccesible=T|IndexInSheet=5|OwnerPartId=1|LineWidth=1|Color=16711680|LocationCount=2|X1=510|Y1=543|X2=510|Y2=560
|RECORD=6|OwnerIndex=150|IsNotAccesible=T|IndexInSheet=6|OwnerPartId=1|LineWidth=1|Color=16711680|LocationCount=2|X1=508|Y1=563|X2=530|Y2=563
|RECORD=6|OwnerIndex=150|IsNotAccesible=T|IndexInSheet=7|OwnerPartId=1|LineWidth=1|Color=16711680|LocationCount=2|X1=522|Y1=543|X2=510|Y2=543
|RECORD=6|OwnerIndex=150|IsNotAccesible=T|IndexInSheet=8|OwnerPartId=1|LineWidth=1|Color=16711680|LocationCount=2|X1=530|Y1=543|X2=522|Y2=543
|RECORD=6|OwnerIndex=150|IsNotAccesible=T|IndexInSheet=9|OwnerPartId=1|LineWidth=1|Color=16711680|LocationCount=2|X1=530|Y1=543|X2=540|Y2=543
|RECORD=6|OwnerIndex=150|IsNotAccesible=T|IndexInSheet=10|OwnerPartId=1|LineWidth=1|Color=16711680|LocationCount=3|X1=520|Y1=550|X2=540|Y2=550|X3=528|Y3=550
|RECORD=8|OwnerIndex=150|IsNotAccesible=T|IndexInSheet=11|OwnerPartId=1|Location.X=510|Location.Y=550|Radius=1|SecondaryRadius=1|Color=16711680|AreaColor=16711680|IsSolid=T
|RECORD=6|OwnerIndex=150|IsNotAccesible=T|IndexInSheet=12|OwnerPartId=1|LineWidth=1|Color=16711680|LocationCount=2|X1=508|Y1=561|X2=513|Y2=561
|RECORD=6|OwnerIndex=150|IsNotAccesible=T|IndexInSheet=13|OwnerPartId=1|LineWidth=1|Color=16711680|LocationCount=2|X1=517|Y1=561|X2=523|Y2=561
|RECORD=6|OwnerIndex=150|IsNotAccesible=T|IndexInSheet=14|OwnerPartId=1|LineWidth=1|Color=16711680|LocationCount=2|X1=530|Y1=561|X2=526|Y2=561
|RECORD=6|OwnerIndex=150|IsNotAccesible=T|IndexInSheet=15|OwnerPartId=1|LineWidth=1|Color=16711680|LocationCount=2|X1=528|Y1=561|X2=528|Y2=550
|RECORD=8|OwnerIndex=150|IsNotAccesible=T|IndexInSheet=16|OwnerPartId=1|Location.X=528|Location.Y=550|Radius=1|SecondaryRadius=1|Color=16711680|AreaColor=16711680|IsSolid=T
|RECORD=6|OwnerIndex=150|IsNotAccesible=T|IndexInSheet=17|OwnerPartId=1|LineWidth=1|Color=16711680|LocationCount=2|X1=540|Y1=543|X2=540|Y2=550
|RECORD=8|OwnerIndex=150|IsNotAccesible=T|IndexInSheet=18|OwnerPartId=1|Location.X=540|Location.Y=550|Radius=1|SecondaryRadius=1|Color=16711680|AreaColor=16711680|IsSolid=T
|RECORD=8|OwnerIndex=150|IsNotAccesible=T|IndexInSheet=19|OwnerPartId=1|Location.X=530|Location.Y=570|Radius=1|SecondaryRadius=1|Color=16711680|AreaColor=16711680|IsSolid=T
|RECORD=7|OwnerIndex=150|IsNotAccesible=T|IndexInSheet=20|OwnerPartId=1|Color=16711680|AreaColor=16711680|IsSolid=T|LocationCount=3|X1=520|Y1=550|X2=518|Y2=556|X3=522|Y3=556
|RECORD=6|OwnerIndex=150|IsNotAccesible=T|IndexInSheet=21|OwnerPartId=1|LineWidth=1|Color=16711680|LocationCount=2|X1=520|Y1=561|X2=520|Y2=555
|RECORD=7|OwnerIndex=150|IsNotAccesible=T|IndexInSheet=22|OwnerPartId=1|Color=16711680|AreaColor=16711680|IsSolid=T|LocationCount=3|X1=522|Y1=546|X2=522|Y2=540|X3=527|Y3=543
|RECORD=6|OwnerIndex=150|IsNotAccesible=T|IndexInSheet=23|OwnerPartId=1|LineWidth=1|Color=16711680|LocationCount=2|X1=526|Y1=546|X2=526|Y2=540
|RECORD=41|OwnerIndex=150|IndexInSheet=24|OwnerPartId=-1|Location.X=478|Location.Y=602|Color=8388608|FontID=1|IsHidden=T|Text=Yes|Name=RoHS|IsMirrored=T
|RECORD=41|OwnerIndex=150|IndexInSheet=25|OwnerPartId=-1|Location.X=478|Location.Y=602|Color=8388608|FontID=1|IsHidden=T|Name=Series|IsMirrored=T
|RECORD=41|OwnerIndex=150|IndexInSheet=26|OwnerPartId=-1|Location.X=478|Location.Y=602|Color=8388608|FontID=1|IsHidden=T|Text=960mW (Ta)|Name=Power Dissipation (Max)|IsMirrored=T
|RECORD=41|OwnerIndex=150|IndexInSheet=27|OwnerPartId=-1|Location.X=478|Location.Y=602|Color=8388608|FontID=1|IsHidden=T|Name=Resistor - Base (R1)|IsMirrored=T
|RECORD=41|OwnerIndex=150|IndexInSheet=28|OwnerPartId=-1|Location.X=478|Location.Y=602|Color=8388608|FontID=1|IsHidden=T|Name=Gain|IsMirrored=T
|RECORD=41|OwnerIndex=150|IndexInSheet=29|OwnerPartId=-1|Location.X=478|Location.Y=602|Color=8388608|FontID=1|IsHidden=T|Name=FET Feature|IsMirrored=T
|RECORD=41|OwnerIndex=150|IndexInSheet=30|OwnerPartId=-1|Location.X=478|Location.Y=602|Color=8388608|FontID=1|IsHidden=T|Name=IGBT Type|IsMirrored=T
|RECORD=41|OwnerIndex=150|IndexInSheet=31|OwnerPartId=-1|Location.X=478|Location.Y=602|Color=8388608|FontID=1|IsHidden=T|Name=Configuration|IsMirrored=T
|RECORD=41|OwnerIndex=150|IndexInSheet=32|OwnerPartId=-1|Location.X=478|Location.Y=602|Color=8388608|FontID=1|IsHidden=T|Name=Frequency|IsMirrored=T
|RECORD=41|OwnerIndex=150|IndexInSheet=33|OwnerPartId=-1|Location.X=478|Location.Y=602|Color=8388608|FontID=1|IsHidden=T|Text=FETs, MOSFETs - Single|Name=Category|IsMirrored=T
|RECORD=41|OwnerIndex=150|IndexInSheet=34|OwnerPartId=-1|Location.X=478|Location.Y=602|Color=8388608|FontID=1|IsHidden=T|Text=1.8V, 4.5V|Name=Drive Voltage (Max Rds On, Min Rds On)|IsMirrored=T
|RECORD=41|OwnerIndex=150|IndexInSheet=35|OwnerPartId=-1|Location.X=478|Location.Y=602|Color=8388608|FontID=1|IsHidden=T|Name=Voltage - Rated|IsMirrored=T
|RECORD=41|OwnerIndex=150|IndexInSheet=36|OwnerPartId=-1|Location.X=478|Location.Y=602|Color=8388608|FontID=1|IsHidden=T|Name=Current - Collector (Ic) (Max)|IsMirrored=T
|RECORD=41|OwnerIndex=150|IndexInSheet=37|OwnerPartId=-1|Location.X=478|Location.Y=602|Color=8388608|FontID=1|IsHidden=T|Text=8 V|Name=Drain to Source Voltage (Vdss)|IsMirrored=T
|RECORD=41|OwnerIndex=150|IndexInSheet=38|OwnerPartId=-1|Location.X=478|Location.Y=602|Color=8388608|FontID=1|IsHidden=T|Name=Voltage - Supply, Single (V+)|IsMirrored=T
|RECORD=41|OwnerIndex=150|IndexInSheet=39|OwnerPartId=-1|Location.X=478|Location.Y=602|Color=8388608|FontID=1|IsHidden=T|Name=Vce Saturation (Max) @ Ib, Ic|IsMirrored=T
|RECORD=41|OwnerIndex=150|IndexInSheet=40|OwnerPartId=-1|Location.X=478|Location.Y=602|Color=8388608|FontID=1|IsHidden=T|Name=Voltage - Test|IsMirrored=T
|RECORD=41|OwnerIndex=150|IndexInSheet=41|OwnerPartId=-1|Location.X=478|Location.Y=602|Color=8388608|FontID=1|IsHidden=T|Name=Input|IsMirrored=T
|RECORD=41|OwnerIndex=150|IndexInSheet=42|OwnerPartId=-1|Location.X=478|Location.Y=602|Color=8388608|FontID=1|IsHidden=T|Text=TO-236-3, SC-59, SOT-23-3|Name=Case/Package|IsMirrored=T
|RECORD=41|OwnerIndex=150|IndexInSheet=43|OwnerPartId=-1|Location.X=478|Location.Y=602|Color=8388608|FontID=1|IsHidden=T|Name=Power - Max|IsMirrored=T
|RECORD=41|OwnerIndex=150|IndexInSheet=44|OwnerPartId=-1|Location.X=478|Location.Y=602|Color=8388608|FontID=1|IsHidden=T|Text=onsemi|Name=Manufacturer|IsMirrored=T
|RECORD=41|OwnerIndex=150|IndexInSheet=45|OwnerPartId=-1|Location.X=478|Location.Y=602|Color=8388608|FontID=1|IsHidden=T|Name=Current - Peak|IsMirrored=T
|RECORD=41|OwnerIndex=150|IndexInSheet=46|OwnerPartId=-1|Location.X=478|Location.Y=602|Color=8388608|FontID=1|IsHidden=T|Text=150°C|Name=Max Operating Temperature|IsMirrored=T
|RECORD=41|OwnerIndex=150|IndexInSheet=47|OwnerPartId=-1|Location.X=478|Location.Y=602|Color=8388608|FontID=1|IsHidden=T|Text=Surface Mount|Name=Mounting Type|IsMirrored=T
|RECORD=41|OwnerIndex=150|IndexInSheet=48|OwnerPartId=-1|Location.X=478|Location.Y=602|Color=8388608|FontID=1|IsHidden=T|Text=MOSFET (Metal Oxide)|Name=Technology|IsMirrored=T
|RECORD=41|OwnerIndex=150|IndexInSheet=49|OwnerPartId=-1|Location.X=478|Location.Y=602|Color=8388608|FontID=1|IsHidden=T|Name=Current Rating (Amps)|IsMirrored=T
|RECORD=41|OwnerIndex=150|IndexInSheet=50|OwnerPartId=-1|Location.X=504|Location.Y=513|Color=8388608|FontID=1|Text=NTR2101PT1G|Name=Manufacturer Part Number|IsMirrored=T
|RECORD=41|OwnerIndex=150|IndexInSheet=51|OwnerPartId=-1|Location.X=478|Location.Y=602|Color=8388608|FontID=1|IsHidden=T|Name=Voltage - Collector Emitter Breakdown (Max)|IsMirrored=T
|RECORD=41|OwnerIndex=150|IndexInSheet=52|OwnerPartId=-1|Location.X=478|Location.Y=602|Color=8388608|FontID=1|IsHidden=T|Name=Resistor - Emitter Base (R2)|IsMirrored=T
|RECORD=41|OwnerIndex=150|IndexInSheet=53|OwnerPartId=-1|Location.X=478|Location.Y=602|Color=8388608|FontID=1|IsHidden=T|Text=1173 pF @ 4 V|Name=Input Capacitance (Ciss) (Max) @ Vds|IsMirrored=T
|RECORD=41|OwnerIndex=150|IndexInSheet=54|OwnerPartId=-1|Location.X=478|Location.Y=602|Color=8388608|FontID=1|IsHidden=T|Text=52mOhm @ 3.5A, 4.5V|Name=Rds On (Max) @ Id, Vgs|IsMirrored=T
|RECORD=41|OwnerIndex=150|IndexInSheet=55|OwnerPartId=-1|Location.X=478|Location.Y=602|Color=8388608|FontID=1|IsHidden=T|Text=NTR2101PT1GOSCT-ND|Name=Supplier Part Number 1|IsMirrored=T
|RECORD=41|OwnerIndex=150|IndexInSheet=56|OwnerPartId=-1|Location.X=478|Location.Y=602|Color=8388608|FontID=1|IsHidden=T|Text=-55°C|Name=Min Operating Temperature|IsMirrored=T
|RECORD=41|OwnerIndex=150|IndexInSheet=57|OwnerPartId=-1|Location.X=478|Location.Y=602|Color=8388608|FontID=1|IsHidden=T|Name=Frequency - Transition|IsMirrored=T
|RECORD=41|OwnerIndex=150|IndexInSheet=58|OwnerPartId=-1|Location.X=478|Location.Y=602|Color=8388608|FontID=1|IsHidden=T|Name=Voltage|IsMirrored=T
|RECORD=41|OwnerIndex=150|IndexInSheet=59|OwnerPartId=-1|Location.X=478|Location.Y=602|Color=8388608|FontID=1|IsHidden=T|Text=P-Channel|Name=FET Type|IsMirrored=T
|RECORD=41|OwnerIndex=150|IndexInSheet=60|OwnerPartId=-1|Location.X=478|Location.Y=602|Color=8388608|FontID=1|IsHidden=T|Text=3.7A (Ta)|Name=Current - Continuous Drain (Id) @ 25°C|IsMirrored=T
|RECORD=41|OwnerIndex=150|IndexInSheet=61|OwnerPartId=-1|Location.X=478|Location.Y=602|Color=8388608|FontID=1|IsHidden=T|Name=Transistor Type|IsMirrored=T
|RECORD=41|OwnerIndex=150|IndexInSheet=62|OwnerPartId=-1|Location.X=478|Location.Y=602|Color=8388608|FontID=2|IsHidden=T|Text=https://www.digikey.com/en/products/detail/onsemi/ntr2101pt1g/687095|Name=Datasheet URL|IsMirrored=T
|RECORD=41|OwnerIndex=150|IndexInSheet=63|OwnerPartId=-1|Location.X=478|Location.Y=602|Color=8388608|FontID=1|IsHidden=T|Name=Applications|IsMirrored=T
|RECORD=41|OwnerIndex=150|IndexInSheet=64|OwnerPartId=-1|Location.X=478|Location.Y=602|Color=8388608|FontID=1|IsHidden=T|Text=839-00735-00|Name=Internal Part Number|IsMirrored=T
|RECORD=41|OwnerIndex=150|IndexInSheet=65|OwnerPartId=-1|Location.X=478|Location.Y=602|Color=8388608|FontID=1|IsHidden=T|Text=Digikey|Name=Supplier 1|IsMirrored=T
|RECORD=41|OwnerIndex=150|IndexInSheet=66|OwnerPartId=-1|Location.X=478|Location.Y=602|Color=8388608|FontID=1|IsHidden=T|Name=DC Current Gain (hFE) (Min) @ Ic, Vce|IsMirrored=T
|RECORD=41|OwnerIndex=150|IndexInSheet=67|OwnerPartId=-1|Location.X=478|Location.Y=602|Color=8388608|FontID=1|IsHidden=T|Name=Resistance - RDS(On)|IsMirrored=T
|RECORD=41|OwnerIndex=150|IndexInSheet=68|OwnerPartId=-1|Location.X=478|Location.Y=602|Color=8388608|FontID=1|IsHidden=T|Name=Current - Collector Cutoff (Max)|IsMirrored=T
|RECORD=34|OwnerIndex=150|IndexInSheet=-1|OwnerPartId=-1|Location.X=504|Location.Y=523|Color=8388608|FontID=1|Text=Q1|Name=Designator|ReadOnlyState=1|IsMirrored=T
|RECORD=41|OwnerIndex=150|IndexInSheet=-1|OwnerPartId=-1|Location.X=478|Location.Y=602|Color=8388608|FontID=1|IsHidden=T|Text=onsemi_NTR2101PT1G|Name=Comment|IsMirrored=T
|RECORD=44|OwnerIndex=150
|RECORD=45|OwnerIndex=225|IndexInSheet=-1|Description=SOT23, 3pins, Body Size 3.0x1.40x1.12mm, T-T = 2.40mm|UseComponentLibrary=T|ModelName=SOT23_3pins_300x140x112|ModelType=PCBLIB|DatafileCount=1|ModelDatafileEntity0=SOT23_3pins_300x140x112|ModelDatafileKind0=PCBLib|IsCurrent=T|DatalinksLocked=T|DatabaseDatalinksLocked=T
|RECORD=46|OwnerIndex=226
|RECORD=47|OwnerIndex=227|DesImpCount=1|DesImp0=null
|RECORD=48|OwnerIndex=226
|RECORD=41|OwnerIndex=229|IndexInSheet=-1|OwnerPartId=-1|Color=8388608|FontID=1|IsHidden=T|Text=2D|Name=Available Preview Images
|RECORD=41|IndexInSheet=2|OwnerPartId=-1|Location.X=19|Location.Y=9|Color=8388608|FontID=1|IsHidden=T|Text=sch_PageDescription|Name=sch_PageDescription
|RECORD=41|IndexInSheet=3|OwnerPartId=-1|Location.X=179|Location.Y=5|Color=8388608|FontID=1|IsHidden=T|Text=sch_PageTitle|Name=sch_PageTitle
|RECORD=41|IndexInSheet=4|OwnerPartId=-1|Location.X=179|Location.Y=5|Color=8388608|FontID=1|IsHidden=T|Text=*|Name=PageDate
|RECORD=41|IndexInSheet=5|OwnerPartId=-1|Color=8388608|FontID=1|IsHidden=T|Text=*|Name=CurrentTime
|RECORD=41|IndexInSheet=6|OwnerPartId=-1|Color=8388608|FontID=1|IsHidden=T|Text=*|Name=CurrentDate
|RECORD=41|IndexInSheet=7|OwnerPartId=-1|Color=8388608|FontID=1|IsHidden=T|Text=*|Name=Time
|RECORD=41|IndexInSheet=8|OwnerPartId=-1|Color=8388608|FontID=1|IsHidden=T|Text=*|Name=Date
|RECORD=41|IndexInSheet=9|OwnerPartId=-1|Color=8388608|FontID=1|IsHidden=T|Text=*|Name=DocumentFullPathAndName
|RECORD=41|IndexInSheet=10|OwnerPartId=-1|Color=8388608|FontID=1|IsHidden=T|Text=*|Name=DocumentName
|RECORD=41|IndexInSheet=11|OwnerPartId=-1|Color=8388608|FontID=1|IsHidden=T|Text=*|Name=ModifiedDate
|RECORD=41|IndexInSheet=12|OwnerPartId=-1|Color=8388608|FontID=1|IsHidden=T|Text=*|Name=ApprovedBy
|RECORD=41|IndexInSheet=13|OwnerPartId=-1|Color=8388608|FontID=1|IsHidden=T|Text=*|Name=CheckedBy
|RECORD=41|IndexInSheet=14|OwnerPartId=-1|Color=8388608|FontID=1|IsHidden=T|Text=*|Name=Author
|RECORD=41|IndexInSheet=15|OwnerPartId=-1|Color=8388608|FontID=1|IsHidden=T|Text=*|Name=CompanyName
|RECORD=41|IndexInSheet=16|OwnerPartId=-1|Color=8388608|FontID=1|IsHidden=T|Text=*|Name=DrawnBy
|RECORD=41|IndexInSheet=17|OwnerPartId=-1|Color=8388608|FontID=1|IsHidden=T|Text=*|Name=Engineer
|RECORD=41|IndexInSheet=18|OwnerPartId=-1|Color=8388608|FontID=1|IsHidden=T|Text=ORGANIZATION|Name=Organization
|RECORD=41|IndexInSheet=19|OwnerPartId=-1|Color=8388608|FontID=1|IsHidden=T|Text=ADDRESS 1|Name=Address1
|RECORD=41|IndexInSheet=20|OwnerPartId=-1|Color=8388608|FontID=1|IsHidden=T|Text=ADDRESS 2|Name=Address2
|RECORD=41|IndexInSheet=21|OwnerPartId=-1|Color=8388608|FontID=1|IsHidden=T|Text=ADDRESS 3|Name=Address3
|RECORD=41|IndexInSheet=22|OwnerPartId=-1|Color=8388608|FontID=1|IsHidden=T|Text=ADDRESS 4|Name=Address4
|RECORD=41|IndexInSheet=23|OwnerPartId=-1|Color=8388608|FontID=1|IsHidden=T|Text=*|Name=Title
|RECORD=41|IndexInSheet=24|OwnerPartId=-1|Color=8388608|FontID=1|IsHidden=T|Text=*|Name=DocumentNumber
|RECORD=41|IndexInSheet=25|OwnerPartId=-1|Color=8388608|FontID=1|IsHidden=T|Text=-|Name=Revision
|RECORD=41|IndexInSheet=26|OwnerPartId=-1|Color=8388608|FontID=1|IsHidden=T|Text=3|Name=SheetNumber
|RECORD=41|IndexInSheet=27|OwnerPartId=-1|Color=8388608|FontID=1|IsHidden=T|Text=3|Name=SheetTotal
|RECORD=41|IndexInSheet=28|OwnerPartId=-1|Color=8388608|FontID=1|IsHidden=T|Text=*|Name=ImagePath|ReadOnlyState=1
|RECORD=41|IndexInSheet=29|OwnerPartId=-1|Color=8388608|FontID=1|IsHidden=T|Text=*|Name=Rule|ReadOnlyState=1
|RECORD=41|IndexInSheet=30|OwnerPartId=-1|Color=8388608|FontID=1|IsHidden=T|Text=*|Name=ProjectName|ReadOnlyState=1
|RECORD=41|IndexInSheet=31|OwnerPartId=-1|Location.X=839|Location.Y=9|Color=8388608|FontID=1|IsHidden=T|Text=*|Name=Title2
|RECORD=41|IndexInSheet=32|OwnerPartId=-1|Location.Y=-10|Color=8388608|FontID=1|IsHidden=T|Text=*|Name=Project
|RECORD=41|IndexInSheet=33|OwnerPartId=-1|Location.Y=-10|Color=8388608|FontID=1|IsHidden=T|Text=--/--/--|Name=ENG_APP_DATE
|RECORD=41|IndexInSheet=34|OwnerPartId=-1|Location.Y=-10|Color=8388608|FontID=1|IsHidden=T|Text=--/--/--|Name=DSN_APP_DATE
|RECORD=41|IndexInSheet=35|OwnerPartId=-1|Location.Y=-10|Color=8388608|FontID=1|IsHidden=T|Text=--/--/--|Name=CHK_APP_DATE
|RECORD=41|IndexInSheet=36|OwnerPartId=-1|Color=8388608|FontID=1|IsHidden=T|Text=*|Name=Application_BuildNumber|ReadOnlyState=1
|RECORD=1|LibReference=1029c3af85768c4190bb7ad29bc67b5|ComponentDescription=1kO ±1% 0.063W 0402 Thick Film Chip Resistor AEC-Q200 compliant|PartCount=2|DisplayModeCount=1|IndexInSheet=37|OwnerPartId=-1|Location.X=460|Location.Y=430|Orientation=1|CurrentPartId=1|LibraryPath=*|SourceLibraryName=Altium Content Vault|TargetFileName=*|AreaColor=11599871|Color=128|PartIDLocked=T|DesignItemId=CMP-26527-000026-1|AllPinCount=2
|RECORD=2|OwnerIndex=266|OwnerPartId=1|Electrical=4|PinConglomerate=35|PinLength=20|Location.X=460|Location.Y=450|Name=1|Designator=1|PinPropagationDelay=0.000000E+000
|RECORD=2|OwnerIndex=266|OwnerPartId=1|Electrical=4|PinConglomerate=33|PinLength=20|Location.X=460|Location.Y=480|Name=2|Designator=2|PinPropagationDelay=0.000000E+000
|RECORD=13|OwnerIndex=266|IsNotAccesible=T|IndexInSheet=2|OwnerPartId=1|Location.X=460|Location.Y=450|Corner.X=455|Corner.Y=453|LineWidth=1|Color=16711680
|RECORD=13|OwnerIndex=266|IsNotAccesible=T|IndexInSheet=3|OwnerPartId=1|Location.X=455|Location.Y=453|Corner.X=465|Corner.Y=458|LineWidth=1|Color=16711680
|RECORD=13|OwnerIndex=266|IsNotAccesible=T|IndexInSheet=4|OwnerPartId=1|Location.X=465|Location.Y=458|Corner.X=455|Corner.Y=463|LineWidth=1|Color=16711680
|RECORD=13|OwnerIndex=266|IsNotAccesible=T|IndexInSheet=5|OwnerPartId=1|Location.X=455|Location.Y=463|Corner.X=465|Corner.Y=468|LineWidth=1|Color=16711680
|RECORD=13|OwnerIndex=266|IsNotAccesible=T|IndexInSheet=6|OwnerPartId=1|Location.X=465|Location.Y=468|Corner.X=455|Corner.Y=473|LineWidth=1|Color=16711680
|RECORD=13|OwnerIndex=266|IsNotAccesible=T|IndexInSheet=7|OwnerPartId=1|Location.X=455|Location.Y=473|Corner.X=465|Corner.Y=478|LineWidth=1|Color=16711680
|RECORD=13|OwnerIndex=266|IsNotAccesible=T|IndexInSheet=8|OwnerPartId=1|Location.X=465|Location.Y=478|Corner.X=460|Corner.Y=480|LineWidth=1|Color=16711680
|RECORD=13|OwnerIndex=266|IsNotAccesible=T|IndexInSheet=9|OwnerPartId=1|Location.X=460|Location.Y=450|Corner.X=460|Corner.Y=447|LineWidth=1|Color=16711680
|RECORD=13|OwnerIndex=266|IsNotAccesible=T|IndexInSheet=10|OwnerPartId=1|Location.X=460|Location.Y=480|Corner.X=460|Corner.Y=483|LineWidth=1|Color=16711680
|RECORD=41|OwnerIndex=266|IndexInSheet=11|OwnerPartId=-1|Location.X=454|Location.Y=502|Color=8388608|FontID=1|IsHidden=T|Text=1mm|Name=Length
|RECORD=41|OwnerIndex=266|IndexInSheet=12|OwnerPartId=-1|Location.X=454|Location.Y=502|Color=8388608|FontID=1|IsHidden=T|Text=Yes|Name=RoHS Compliant
|RECORD=41|OwnerIndex=266|IndexInSheet=13|OwnerPartId=-1|Location.X=454|Location.Y=502|Color=8388608|FontID=1|IsHidden=T|Text=Rectangular|Name=Construction
|RECORD=41|OwnerIndex=266|IndexInSheet=14|OwnerPartId=-1|Location.X=454|Location.Y=502|Color=8388608|FontID=1|IsHidden=T|Text=0.016inch|Name=Height
|RECORD=41|OwnerIndex=266|IndexInSheet=15|OwnerPartId=-1|Location.X=454|Location.Y=502|Color=8388608|FontID=1|IsHidden=T|Text=0402|Name=Size Code
|RECORD=41|OwnerIndex=266|IndexInSheet=16|OwnerPartId=-1|Location.X=454|Location.Y=502|Color=8388608|FontID=1|IsHidden=T|Text=Lead Free|Name=Lead Free
|RECORD=41|OwnerIndex=266|IndexInSheet=17|OwnerPartId=-1|Location.X=454|Location.Y=502|Color=8388608|FontID=1|IsHidden=T|Text=No|Name=Radiation Hardening
|RECORD=41|OwnerIndex=266|IndexInSheet=18|OwnerPartId=-1|Location.X=454|Location.Y=502|Color=8388608|FontID=1|IsHidden=T|Text=1%|Name=Tolerance
|RECORD=41|OwnerIndex=266|IndexInSheet=19|OwnerPartId=-1|Location.X=454|Location.Y=502|Color=8388608|FontID=1|IsHidden=T|Text=0.02inch|Name=Width
|RECORD=41|OwnerIndex=266|IndexInSheet=20|OwnerPartId=-1|Location.X=454|Location.Y=502|Color=8388608|FontID=1|IsHidden=T|Text=1kR|Name=Resistance
|RECORD=41|OwnerIndex=266|IndexInSheet=21|OwnerPartId=-1|Location.X=454|Location.Y=502|Color=8388608|FontID=1|IsHidden=T|Text=Not|Name=Military Standard
|RECORD=41|OwnerIndex=266|IndexInSheet=22|OwnerPartId=-1|Location.X=454|Location.Y=502|Color=8388608|FontID=1|IsHidden=T|Text=Thick Film|Name=Resistor Type
|RECORD=41|OwnerIndex=266|IndexInSheet=23|OwnerPartId=-1|Location.X=454|Location.Y=502|Color=8388608|FontID=1|IsHidden=T|Text=100ppm/°C|Name=Temperature Coefficient
|RECORD=41|OwnerIndex=266|IndexInSheet=24|OwnerPartId=-1|Location.X=454|Location.Y=502|Color=8388608|FontID=1|IsHidden=T|Text=2|Name=Number of Terminations
|RECORD=41|OwnerIndex=266|IndexInSheet=25|OwnerPartId=-1|Location.X=454|Location.Y=502|Color=8388608|FontID=1|IsHidden=T|Text=-55°C|Name=Min Operating Temperature
|RECORD=41|OwnerIndex=266|IndexInSheet=26|OwnerPartId=-1|Location.X=454|Location.Y=502|Color=8388608|FontID=1|IsHidden=T|Text=155°C|Name=Max Operating Temperature
|RECORD=41|OwnerIndex=266|IndexInSheet=27|OwnerPartId=-1|Location.X=454|Location.Y=502|Color=8388608|FontID=1|IsHidden=T|Text=63mW|Name=Power Rating
|RECORD=41|OwnerIndex=266|IndexInSheet=28|OwnerPartId=-1|Location.X=454|Location.Y=502|Color=8388608|FontID=1|IsHidden=T|Text=0.5mm|Name=Depth
|RECORD=41|OwnerIndex=266|IndexInSheet=29|OwnerPartId=-1|Location.X=454|Location.Y=502|Color=8388608|FontID=1|IsHidden=T|Text=Automotive AEC-Q200|Name=Features
|RECORD=41|OwnerIndex=266|IndexInSheet=30|OwnerPartId=-1|Location.X=454|Location.Y=502|Color=8388608|FontID=1|IsHidden=T|Text=Tape and Reel|Name=Packaging
|RECORD=41|OwnerIndex=266|IndexInSheet=31|OwnerPartId=-1|Location.X=454|Location.Y=502|Color=8388608|FontID=1|IsHidden=T|Text=1005|Name=Case Code (Metric)
|RECORD=41|OwnerIndex=266|IndexInSheet=32|OwnerPartId=-1|Location.X=454|Location.Y=502|Color=8388608|FontID=1|IsHidden=T|Text=Surface Mount|Name=Mount
|RECORD=41|OwnerIndex=266|IndexInSheet=33|OwnerPartId=-1|Location.X=454|Location.Y=502|Color=8388608|FontID=1|IsHidden=T|Text=Tin|Name=Contact Plating
|RECORD=41|OwnerIndex=266|IndexInSheet=34|OwnerPartId=-1|Location.X=454|Location.Y=502|Color=8388608|FontID=1|IsHidden=T|Text=63mW|Name=Max Power Dissipation
|RECORD=41|OwnerIndex=266|IndexInSheet=35|OwnerPartId=-1|Location.X=454|Location.Y=502|Color=8388608|FontID=1|IsHidden=T|Text=0402|Name=Case/Package
|RECORD=41|OwnerIndex=266|IndexInSheet=36|OwnerPartId=-1|Location.X=454|Location.Y=502|Color=8388608|FontID=1|IsHidden=T|Text=0402|Name=Case Code (Imperial)
|RECORD=41|OwnerIndex=266|IndexInSheet=37|OwnerPartId=-1|Location.X=454|Location.Y=502|Color=8388608|FontID=1|IsHidden=T|Text=RMCF|Name=Series
|RECORD=34|OwnerIndex=266|IndexInSheet=-1|OwnerPartId=-1|Location.X=466|Location.Y=474|Color=8388608|FontID=1|Text=R10|Name=Designator|ReadOnlyState=1
|RECORD=41|OwnerIndex=266|IndexInSheet=-1|OwnerPartId=1|Location.X=466|Location.Y=464|Color=8388608|FontID=1|Text=1k|Name=Comment
|RECORD=44|OwnerIndex=266
|RECORD=45|OwnerIndex=309|IndexInSheet=-1|UseComponentLibrary=T|ModelName=FP-RMCF0402-MFG|ModelType=PCBLIB|DatafileCount=1|ModelDatafileEntity0=FP-RMCF0402-MFG|ModelDatafileKind0=PCBLib|IsCurrent=T|DatalinksLocked=T|DatabaseDatalinksLocked=T
|RECORD=46|OwnerIndex=310
|RECORD=48|OwnerIndex=310
|RECORD=45|OwnerIndex=309|IndexInSheet=-1|UseComponentLibrary=T|ModelName=FP-RMCF0402-IPC_C|ModelType=PCBLIB|DatafileCount=1|ModelDatafileEntity0=FP-RMCF0402-IPC_C|ModelDatafileKind0=PCBLib|DatalinksLocked=T|DatabaseDatalinksLocked=T
|RECORD=46|OwnerIndex=313
|RECORD=48|OwnerIndex=313
|RECORD=45|OwnerIndex=309|IndexInSheet=-1|UseComponentLibrary=T|ModelName=FP-RMCF0402-IPC_B|ModelType=PCBLIB|DatafileCount=1|ModelDatafileEntity0=FP-RMCF0402-IPC_B|ModelDatafileKind0=PCBLib|DatalinksLocked=T|DatabaseDatalinksLocked=T
|RECORD=46|OwnerIndex=316
|RECORD=48|OwnerIndex=316
|RECORD=45|OwnerIndex=309|IndexInSheet=-1|UseComponentLibrary=T|ModelName=FP-RMCF0402-IPC_A|ModelType=PCBLIB|DatafileCount=1|ModelDatafileEntity0=FP-RMCF0402-IPC_A|ModelDatafileKind0=PCBLib|DatalinksLocked=T|DatabaseDatalinksLocked=T
|RECORD=46|OwnerIndex=319
|RECORD=48|OwnerIndex=319
|RECORD=1|LibReference=1029c3af85768c4190bb7ad29bc67b5|ComponentDescription=100kO ±1% 0.063W 0402 Thick Film Chip Resistor AEC-Q200 compliant|PartCount=2|DisplayModeCount=1|IndexInSheet=38|OwnerPartId=-1|Location.X=460|Location.Y=320|Orientation=1|CurrentPartId=1|LibraryPath=*|SourceLibraryName=Altium Content Vault|TargetFileName=*|AreaColor=11599871|Color=128|PartIDLocked=T|DesignItemId=CMP-2000-06984-2|AllPinCount=2
|RECORD=2|OwnerIndex=322|OwnerPartId=1|Electrical=4|PinConglomerate=35|PinLength=20|Location.X=460|Location.Y=340|Name=1|Designator=1|PinPropagationDelay=0.000000E+000
|RECORD=2|OwnerIndex=322|OwnerPartId=1|Electrical=4|PinConglomerate=33|PinLength=20|Location.X=460|Location.Y=370|Name=2|Designator=2|PinPropagationDelay=0.000000E+000
|RECORD=13|OwnerIndex=322|IsNotAccesible=T|IndexInSheet=2|OwnerPartId=1|Location.X=460|Location.Y=340|Corner.X=455|Corner.Y=343|LineWidth=1|Color=16711680
|RECORD=13|OwnerIndex=322|IsNotAccesible=T|IndexInSheet=3|OwnerPartId=1|Location.X=455|Location.Y=343|Corner.X=465|Corner.Y=348|LineWidth=1|Color=16711680
|RECORD=13|OwnerIndex=322|IsNotAccesible=T|IndexInSheet=4|OwnerPartId=1|Location.X=465|Location.Y=348|Corner.X=455|Corner.Y=353|LineWidth=1|Color=16711680
|RECORD=13|OwnerIndex=322|IsNotAccesible=T|IndexInSheet=5|OwnerPartId=1|Location.X=455|Location.Y=353|Corner.X=465|Corner.Y=358|LineWidth=1|Color=16711680
|RECORD=13|OwnerIndex=322|IsNotAccesible=T|IndexInSheet=6|OwnerPartId=1|Location.X=465|Location.Y=358|Corner.X=455|Corner.Y=363|LineWidth=1|Color=16711680
|RECORD=13|OwnerIndex=322|IsNotAccesible=T|IndexInSheet=7|OwnerPartId=1|Location.X=455|Location.Y=363|Corner.X=465|Corner.Y=368|LineWidth=1|Color=16711680
|RECORD=13|OwnerIndex=322|IsNotAccesible=T|IndexInSheet=8|OwnerPartId=1|Location.X=465|Location.Y=368|Corner.X=460|Corner.Y=370|LineWidth=1|Color=16711680
|RECORD=13|OwnerIndex=322|IsNotAccesible=T|IndexInSheet=9|OwnerPartId=1|Location.X=460|Location.Y=340|Corner.X=460|Corner.Y=337|LineWidth=1|Color=16711680
|RECORD=13|OwnerIndex=322|IsNotAccesible=T|IndexInSheet=10|OwnerPartId=1|Location.X=460|Location.Y=370|Corner.X=460|Corner.Y=373|LineWidth=1|Color=16711680
|RECORD=41|OwnerIndex=322|IndexInSheet=11|OwnerPartId=-1|Location.X=454|Location.Y=392|Color=8388608|FontID=1|IsHidden=T|Text=63mW|Name=Max Power Dissipation
|RECORD=41|OwnerIndex=322|IndexInSheet=12|OwnerPartId=-1|Location.X=454|Location.Y=392|Color=8388608|FontID=1|IsHidden=T|Text=Tape and Reel|Name=Packaging
|RECORD=41|OwnerIndex=322|IndexInSheet=13|OwnerPartId=-1|Location.X=454|Location.Y=392|Color=8388608|FontID=1|IsHidden=T|Text=0402|Name=Size Code
|RECORD=41|OwnerIndex=322|IndexInSheet=14|OwnerPartId=-1|Location.X=454|Location.Y=392|Color=8388608|FontID=1|IsHidden=T|Text=100kR|Name=Resistance
|RECORD=41|OwnerIndex=322|IndexInSheet=15|OwnerPartId=-1|Location.X=454|Location.Y=392|Color=8388608|FontID=1|IsHidden=T|Text=Thick Film|Name=Resistor Type
|RECORD=41|OwnerIndex=322|IndexInSheet=16|OwnerPartId=-1|Location.X=454|Location.Y=392|Color=8388608|FontID=1|IsHidden=T|Text=Automotive AEC-Q200|Name=Features
|RECORD=41|OwnerIndex=322|IndexInSheet=17|OwnerPartId=-1|Location.X=454|Location.Y=392|Color=8388608|FontID=1|IsHidden=T|Text=100ppm/°C|Name=Temperature Coefficient
|RECORD=41|OwnerIndex=322|IndexInSheet=18|OwnerPartId=-1|Location.X=454|Location.Y=392|Color=8388608|FontID=1|IsHidden=T|Text=1005|Name=Case Code (Metric)
|RECORD=41|OwnerIndex=322|IndexInSheet=19|OwnerPartId=-1|Location.X=454|Location.Y=392|Color=8388608|FontID=1|IsHidden=T|Text=Yes|Name=RoHS Compliant
|RECORD=41|OwnerIndex=322|IndexInSheet=20|OwnerPartId=-1|Location.X=454|Location.Y=392|Color=8388608|FontID=1|IsHidden=T|Text=1mm|Name=Length
|RECORD=41|OwnerIndex=322|IndexInSheet=21|OwnerPartId=-1|Location.X=454|Location.Y=392|Color=8388608|FontID=1|IsHidden=T|Text=No|Name=Radiation Hardening
|RECORD=41|OwnerIndex=322|IndexInSheet=22|OwnerPartId=-1|Location.X=454|Location.Y=392|Color=8388608|FontID=1|IsHidden=T|Text=Not|Name=Military Standard
|RECORD=41|OwnerIndex=322|IndexInSheet=23|OwnerPartId=-1|Location.X=454|Location.Y=392|Color=8388608|FontID=1|IsHidden=T|Text=0402|Name=Case Code (Imperial)
|RECORD=41|OwnerIndex=322|IndexInSheet=24|OwnerPartId=-1|Location.X=454|Location.Y=392|Color=8388608|FontID=1|IsHidden=T|Text=0.5mm|Name=Depth
|RECORD=41|OwnerIndex=322|IndexInSheet=25|OwnerPartId=-1|Location.X=454|Location.Y=392|Color=8388608|FontID=1|IsHidden=T|Text=155°C|Name=Max Operating Temperature
|RECORD=41|OwnerIndex=322|IndexInSheet=26|OwnerPartId=-1|Location.X=454|Location.Y=392|Color=8388608|FontID=1|IsHidden=T|Text=Lead Free|Name=Lead Free
|RECORD=41|OwnerIndex=322|IndexInSheet=27|OwnerPartId=-1|Location.X=454|Location.Y=392|Color=8388608|FontID=1|IsHidden=T|Text=0402|Name=Case/Package
|RECORD=41|OwnerIndex=322|IndexInSheet=28|OwnerPartId=-1|Location.X=454|Location.Y=392|Color=8388608|FontID=1|IsHidden=T|Text=1%|Name=Tolerance
|RECORD=41|OwnerIndex=322|IndexInSheet=29|OwnerPartId=-1|Location.X=454|Location.Y=392|Color=8388608|FontID=1|IsHidden=T|Text=Rectangular|Name=Construction
|RECORD=41|OwnerIndex=322|IndexInSheet=30|OwnerPartId=-1|Location.X=454|Location.Y=392|Color=8388608|FontID=1|IsHidden=T|Text=2|Name=Number of Terminations
|RECORD=41|OwnerIndex=322|IndexInSheet=31|OwnerPartId=-1|Location.X=454|Location.Y=392|Color=8388608|FontID=1|IsHidden=T|Text=Surface Mount|Name=Mount
|RECORD=41|OwnerIndex=322|IndexInSheet=32|OwnerPartId=-1|Location.X=454|Location.Y=392|Color=8388608|FontID=1|IsHidden=T|Text=-55°C|Name=Min Operating Temperature
|RECORD=41|OwnerIndex=322|IndexInSheet=33|OwnerPartId=-1|Location.X=454|Location.Y=392|Color=8388608|FontID=1|IsHidden=T|Text=0.02inch|Name=Width
|RECORD=41|OwnerIndex=322|IndexInSheet=34|OwnerPartId=-1|Location.X=454|Location.Y=392|Color=8388608|FontID=1|IsHidden=T|Text=RMCF|Name=Series
|RECORD=41|OwnerIndex=322|IndexInSheet=35|OwnerPartId=-1|Location.X=454|Location.Y=392|Color=8388608|FontID=1|IsHidden=T|Text=Tin|Name=Contact Plating
|RECORD=41|OwnerIndex=322|IndexInSheet=36|OwnerPartId=-1|Location.X=454|Location.Y=392|Color=8388608|FontID=1|IsHidden=T|Text=62.5mW|Name=Power Rating
|RECORD=41|OwnerIndex=322|IndexInSheet=37|OwnerPartId=-1|Location.X=454|Location.Y=392|Color=8388608|FontID=1|IsHidden=T|Text=0.016inch|Name=Height
|RECORD=34|OwnerIndex=322|IndexInSheet=-1|OwnerPartId=-1|Location.X=466|Location.Y=364|Color=8388608|FontID=1|Text=R11|Name=Designator|ReadOnlyState=1
|RECORD=41|OwnerIndex=322|IndexInSheet=-1|OwnerPartId=1|Location.X=466|Location.Y=354|Color=8388608|FontID=1|Text=100k|Name=Comment
|RECORD=44|OwnerIndex=322
|RECORD=45|OwnerIndex=365|IndexInSheet=-1|UseComponentLibrary=T|ModelName=FP-RMCF0402-IPC_C|ModelType=PCBLIB|DatafileCount=1|ModelDatafileEntity0=FP-RMCF0402-IPC_C|ModelDatafileKind0=PCBLib|IsCurrent=T|DatalinksLocked=T|DatabaseDatalinksLocked=T
|RECORD=46|OwnerIndex=366
|RECORD=48|OwnerIndex=366
|RECORD=45|OwnerIndex=365|IndexInSheet=-1|UseComponentLibrary=T|ModelName=FP-RMCF0402-IPC_A|ModelType=PCBLIB|DatafileCount=1|ModelDatafileEntity0=FP-RMCF0402-IPC_A|ModelDatafileKind0=PCBLib|DatalinksLocked=T|DatabaseDatalinksLocked=T
|RECORD=46|OwnerIndex=369
|RECORD=48|OwnerIndex=369
|RECORD=45|OwnerIndex=365|IndexInSheet=-1|UseComponentLibrary=T|ModelName=FP-RMCF0402-IPC_B|ModelType=PCBLIB|DatafileCount=1|ModelDatafileEntity0=FP-RMCF0402-IPC_B|ModelDatafileKind0=PCBLib|DatalinksLocked=T|DatabaseDatalinksLocked=T
|RECORD=46|OwnerIndex=372
|RECORD=48|OwnerIndex=372
|RECORD=45|OwnerIndex=365|IndexInSheet=-1|UseComponentLibrary=T|ModelName=FP-RMCF0402-MFG|ModelType=PCBLIB|DatafileCount=1|ModelDatafileEntity0=FP-RMCF0402-MFG|ModelDatafileKind0=PCBLib|DatalinksLocked=T|DatabaseDatalinksLocked=T
|RECORD=46|OwnerIndex=375
|RECORD=48|OwnerIndex=375
|RECORD=1|LibReference=4cc4b267dca4c8e51f7102f422741d8|ComponentDescription=Multilayer type RF Inductor 47nH ±5% 0.72O 300mA 0402|PartCount=2|DisplayModeCount=1|IndexInSheet=39|OwnerPartId=-1|Location.X=350|Location.Y=290|IsMirrored=T|CurrentPartId=1|LibraryPath=*|SourceLibraryName=Altium Content Vault|TargetFileName=*|AreaColor=11599871|Color=128|PartIDLocked=T|DesignItemId=CMP-06042-015783-1|AllPinCount=2
|RECORD=12|OwnerIndex=378|IsNotAccesible=T|OwnerPartId=1|Location.X=340|Location.Y=290|Radius=5|LineWidth=1|EndAngle=180.000|Color=16711680
|RECORD=12|OwnerIndex=378|IsNotAccesible=T|IndexInSheet=1|OwnerPartId=1|Location.X=330|Location.Y=290|Radius=5|LineWidth=1|EndAngle=180.000|Color=16711680
|RECORD=12|OwnerIndex=378|IsNotAccesible=T|IndexInSheet=2|OwnerPartId=1|Location.X=320|Location.Y=290|Radius=5|LineWidth=1|EndAngle=180.000|Color=16711680
|RECORD=8|OwnerIndex=378|IsNotAccesible=T|IndexInSheet=3|OwnerPartId=1|Location.X=340|Location.Y=290|Radius=1|SecondaryRadius=1|LineWidth=1|Color=16711680
|RECORD=2|OwnerIndex=378|OwnerPartId=1|Electrical=4|PinConglomerate=32|PinLength=5|Location.X=345|Location.Y=290|Name=1|Designator=1|PinPropagationDelay=0.000000E+000
|RECORD=2|OwnerIndex=378|OwnerPartId=1|Electrical=4|PinConglomerate=34|PinLength=5|Location.X=315|Location.Y=290|Name=2|Designator=2|PinPropagationDelay=0.000000E+000
|RECORD=41|OwnerIndex=378|IndexInSheet=6|OwnerPartId=-1|Location.X=308|Location.Y=295|Color=8388608|FontID=1|IsHidden=T|Text=5%|Name=Tolerance|IsMirrored=T
|RECORD=41|OwnerIndex=378|IndexInSheet=7|OwnerPartId=-1|Location.X=308|Location.Y=295|Color=8388608|FontID=1|IsHidden=T|Text=Tape and Reel|Name=Packaging|IsMirrored=T
|RECORD=41|OwnerIndex=378|IndexInSheet=8|OwnerPartId=-1|Location.X=308|Location.Y=295|Color=8388608|FontID=1|IsHidden=T|Text=0402|Name=Case Code (Imperial)|IsMirrored=T
|RECORD=41|OwnerIndex=378|IndexInSheet=9|OwnerPartId=-1|Location.X=308|Location.Y=295|Color=8388608|FontID=1|IsHidden=T|Text=125°C|Name=Max Operating Temperature|IsMirrored=T
|RECORD=41|OwnerIndex=378|IndexInSheet=10|OwnerPartId=-1|Location.X=308|Location.Y=295|Color=8388608|FontID=1|IsHidden=T|Text=Not|Name=Military Standard|IsMirrored=T
|RECORD=41|OwnerIndex=378|IndexInSheet=11|OwnerPartId=-1|Location.X=308|Location.Y=295|Color=8388608|FontID=1|IsHidden=T|Text=Air|Name=Core Material|IsMirrored=T
|RECORD=41|OwnerIndex=378|IndexInSheet=12|OwnerPartId=-1|Location.X=308|Location.Y=295|Color=8388608|FontID=1|IsHidden=T|Text=720mR|Name=DC Resistance (DCR)|IsMirrored=T
|RECORD=41|OwnerIndex=378|IndexInSheet=13|OwnerPartId=-1|Location.X=308|Location.Y=295|Color=8388608|FontID=1|IsHidden=T|Text=1mm|Name=Length|IsMirrored=T
|RECORD=41|OwnerIndex=378|IndexInSheet=14|OwnerPartId=-1|Location.X=308|Location.Y=295|Color=8388608|FontID=1|IsHidden=T|Text=No|Name=Radiation Hardening|IsMirrored=T
|RECORD=41|OwnerIndex=378|IndexInSheet=15|OwnerPartId=-1|Location.X=308|Location.Y=295|Color=8388608|FontID=1|IsHidden=T|Text=0.5mm|Name=Height|IsMirrored=T
|RECORD=41|OwnerIndex=378|IndexInSheet=16|OwnerPartId=-1|Location.X=308|Location.Y=295|Color=8388608|FontID=1|IsHidden=T|Text=-55°C|Name=Min Operating Temperature|IsMirrored=T
|RECORD=41|OwnerIndex=378|IndexInSheet=17|OwnerPartId=-1|Location.X=308|Location.Y=295|Color=8388608|FontID=1|IsHidden=T|Text=0.02inch|Name=Width|IsMirrored=T
|RECORD=41|OwnerIndex=378|IndexInSheet=18|OwnerPartId=-1|Location.X=308|Location.Y=295|Color=8388608|FontID=1|IsHidden=T|Text=47nH|Name=Inductance|IsMirrored=T
|RECORD=41|OwnerIndex=378|IndexInSheet=19|OwnerPartId=-1|Location.X=308|Location.Y=295|Color=8388608|FontID=1|IsHidden=T|Text=Lead Free|Name=Lead Free|IsMirrored=T
|RECORD=41|OwnerIndex=378|IndexInSheet=20|OwnerPartId=-1|Location.X=308|Location.Y=295|Color=8388608|FontID=1|IsHidden=T|Text=SMD/SMT|Name=Termination|IsMirrored=T
|RECORD=41|OwnerIndex=378|IndexInSheet=21|OwnerPartId=-1|Location.X=308|Location.Y=295|Color=8388608|FontID=1|IsHidden=T|Text=200mA|Name=DC Current|IsMirrored=T
|RECORD=41|OwnerIndex=378|IndexInSheet=22|OwnerPartId=-1|Location.X=308|Location.Y=295|Color=8388608|FontID=1|IsHidden=T|Text=0.022inch|Name=Height - Seated (Max)|IsMirrored=T
|RECORD=41|OwnerIndex=378|IndexInSheet=23|OwnerPartId=-1|Location.X=308|Location.Y=295|Color=8388608|FontID=1|IsHidden=T|Text=Unshielded|Name=Shielding|IsMirrored=T
|RECORD=41|OwnerIndex=378|IndexInSheet=24|OwnerPartId=-1|Location.X=308|Location.Y=295|Color=8388608|FontID=1|IsHidden=T|Text=1GHz|Name=Self Resonant Frequency|IsMirrored=T
|RECORD=41|OwnerIndex=378|IndexInSheet=25|OwnerPartId=-1|Location.X=308|Location.Y=295|Color=8388608|FontID=1|IsHidden=T|Text=8|Name=Q Factor|IsMirrored=T
|RECORD=41|OwnerIndex=378|IndexInSheet=26|OwnerPartId=-1|Location.X=308|Location.Y=295|Color=8388608|FontID=1|IsHidden=T|Text=200mA|Name=Rated Current-Max|IsMirrored=T
|RECORD=41|OwnerIndex=378|IndexInSheet=27|OwnerPartId=-1|Location.X=308|Location.Y=295|Color=8388608|FontID=1|IsHidden=T|Text=0402|Name=Case/Package|IsMirrored=T
|RECORD=41|OwnerIndex=378|IndexInSheet=28|OwnerPartId=-1|Location.X=308|Location.Y=295|Color=8388608|FontID=1|IsHidden=T|Text=100MHz|Name=Test Frequency|IsMirrored=T
|RECORD=41|OwnerIndex=378|IndexInSheet=29|OwnerPartId=-1|Location.X=308|Location.Y=295|Color=8388608|FontID=1|IsHidden=T|Text=200mA|Name=Max DC Current|IsMirrored=T
|RECORD=41|OwnerIndex=378|IndexInSheet=30|OwnerPartId=-1|Location.X=308|Location.Y=295|Color=8388608|FontID=1|IsHidden=T|Text=LQG15HS|Name=Series|IsMirrored=T
|RECORD=41|OwnerIndex=378|IndexInSheet=31|OwnerPartId=-1|Location.X=308|Location.Y=295|Color=8388608|FontID=1|IsHidden=T|Text=1005|Name=Case Code (Metric)|IsMirrored=T
|RECORD=41|OwnerIndex=378|IndexInSheet=32|OwnerPartId=-1|Location.X=308|Location.Y=295|Color=8388608|FontID=1|IsHidden=T|Text=Surface Mount|Name=Mount|IsMirrored=T
|RECORD=41|OwnerIndex=378|IndexInSheet=33|OwnerPartId=-1|Location.X=308|Location.Y=295|Color=8388608|FontID=1|IsHidden=T|Text=200mA|Name=Current Rating|IsMirrored=T
|RECORD=41|OwnerIndex=378|IndexInSheet=34|OwnerPartId=-1|Location.X=308|Location.Y=295|Color=8388608|FontID=1|IsHidden=T|Text=0.55mm|Name=Depth|IsMirrored=T
|RECORD=41|OwnerIndex=378|IndexInSheet=35|OwnerPartId=-1|Location.X=308|Location.Y=295|Color=8388608|FontID=1|IsHidden=T|Text=1|Name=Package Quantity|IsMirrored=T
|RECORD=34|OwnerIndex=378|IndexInSheet=-1|OwnerPartId=-1|Location.X=315|Location.Y=295|Color=8388608|FontID=1|Text=L1|Name=Designator|ReadOnlyState=1|IsMirrored=T
|RECORD=41|OwnerIndex=378|IndexInSheet=-1|OwnerPartId=1|Location.X=315|Location.Y=277|Color=8388608|FontID=1|Text=47nH 300mA|Name=Comment|IsMirrored=T
|RECORD=44|OwnerIndex=378
|RECORD=45|OwnerIndex=419|IndexInSheet=-1|UseComponentLibrary=T|ModelName=FP-LQG15HH_02-IPC_B|ModelType=PCBLIB|DatafileCount=1|ModelDatafileEntity0=FP-LQG15HH_02-IPC_B|ModelDatafileKind0=PCBLib|IsCurrent=T|DatalinksLocked=T|DatabaseDatalinksLocked=T
|RECORD=46|OwnerIndex=420
|RECORD=48|OwnerIndex=420
|RECORD=45|OwnerIndex=419|IndexInSheet=-1|UseComponentLibrary=T|ModelName=FP-LQG15HH_02-IPC_A|ModelType=PCBLIB|DatafileCount=1|ModelDatafileEntity0=FP-LQG15HH_02-IPC_A|ModelDatafileKind0=PCBLib|DatalinksLocked=T|DatabaseDatalinksLocked=T
|RECORD=46|OwnerIndex=423
|RECORD=48|OwnerIndex=423
|RECORD=45|OwnerIndex=419|IndexInSheet=-1|UseComponentLibrary=T|ModelName=FP-LQG15HH_02-MFG|ModelType=PCBLIB|DatafileCount=1|ModelDatafileEntity0=FP-LQG15HH_02-MFG|ModelDatafileKind0=PCBLib|DatalinksLocked=T|DatabaseDatalinksLocked=T
|RECORD=46|OwnerIndex=426
|RECORD=48|OwnerIndex=426
|RECORD=45|OwnerIndex=419|IndexInSheet=-1|UseComponentLibrary=T|ModelName=FP-LQG15HH_02-IPC_C|ModelType=PCBLIB|DatafileCount=1|ModelDatafileEntity0=FP-LQG15HH_02-IPC_C|ModelDatafileKind0=PCBLib|DatalinksLocked=T|DatabaseDatalinksLocked=T
|RECORD=46|OwnerIndex=429
|RECORD=48|OwnerIndex=429
|RECORD=1|LibReference=edccc070dd5cba1f9372128faf3915e|ComponentDescription=TVS DIODE 14V 40V 0402|PartCount=2|DisplayModeCount=1|IndexInSheet=40|OwnerPartId=-1|Location.X=290|Location.Y=160|Orientation=1|CurrentPartId=1|LibraryPath=*|SourceLibraryName=Altium Content Vault|TargetFileName=*|AreaColor=11599871|Color=128|PartIDLocked=T|DesignItemId=CMP-08607-000011-1|AllPinCount=2
|RECORD=13|OwnerIndex=432|IsNotAccesible=T|OwnerPartId=1|Location.X=280|Location.Y=190|Corner.X=300|Corner.Y=190|LineWidth=1|Color=16711680
|RECORD=13|OwnerIndex=432|IsNotAccesible=T|IndexInSheet=1|OwnerPartId=1|Location.X=285|Location.Y=210|Corner.X=295|Corner.Y=210|LineWidth=1|Color=16711680
|RECORD=13|OwnerIndex=432|IsNotAccesible=T|IndexInSheet=2|OwnerPartId=1|Location.X=280|Location.Y=190|Corner.X=290|Corner.Y=210|LineWidth=1|Color=16711680
|RECORD=13|OwnerIndex=432|IsNotAccesible=T|IndexInSheet=3|OwnerPartId=1|Location.X=300|Location.Y=190|Corner.X=290|Corner.Y=210|LineWidth=1|Color=16711680
|RECORD=13|OwnerIndex=432|IsNotAccesible=T|IndexInSheet=4|OwnerPartId=1|Location.X=285|Location.Y=210|Corner.X=280|Corner.Y=215|LineWidth=1|Color=16711680
|RECORD=13|OwnerIndex=432|IsNotAccesible=T|IndexInSheet=5|OwnerPartId=1|Location.X=295|Location.Y=210|Corner.X=300|Corner.Y=205|LineWidth=1|Color=16711680
|RECORD=13|OwnerIndex=432|IsNotAccesible=T|IndexInSheet=6|OwnerPartId=1|Location.X=290|Location.Y=210|Corner.X=280|Corner.Y=230|LineWidth=1|Color=16711680
|RECORD=13|OwnerIndex=432|IsNotAccesible=T|IndexInSheet=7|OwnerPartId=1|Location.X=280|Location.Y=230|Corner.X=300|Corner.Y=230|LineWidth=1|Color=16711680
|RECORD=13|OwnerIndex=432|IsNotAccesible=T|IndexInSheet=8|OwnerPartId=1|Location.X=300|Location.Y=230|Corner.X=290|Corner.Y=210|LineWidth=1|Color=16711680
|RECORD=13|OwnerIndex=432|IsNotAccesible=T|IndexInSheet=9|OwnerPartId=1|Location.X=290|Location.Y=190|Corner.X=290|Corner.Y=180|LineWidth=1|Color=16711680
|RECORD=13|OwnerIndex=432|IsNotAccesible=T|IndexInSheet=10|OwnerPartId=1|Location.X=290|Location.Y=230|Corner.X=290|Corner.Y=240|LineWidth=1|Color=16711680
|RECORD=2|OwnerIndex=432|OwnerPartId=1|Electrical=4|PinConglomerate=35|PinLength=20|Location.X=290|Location.Y=180|Name=1|Designator=1|PinPropagationDelay=0.000000E+000
|RECORD=2|OwnerIndex=432|OwnerPartId=1|Electrical=4|PinConglomerate=33|PinLength=20|Location.X=290|Location.Y=240|Name=2|Designator=2|PinPropagationDelay=0.000000E+000
|RECORD=41|OwnerIndex=432|IndexInSheet=13|OwnerPartId=-1|Location.X=279|Location.Y=262|Color=8388608|FontID=1|IsHidden=T|Text=-55°C|Name=Temperature Range Low
|RECORD=41|OwnerIndex=432|IndexInSheet=14|OwnerPartId=-1|Location.X=279|Location.Y=262|Color=8388608|FontID=1|IsHidden=T|Text=Yes|Name=Lead Free
|RECORD=41|OwnerIndex=432|IndexInSheet=15|OwnerPartId=-1|Location.X=279|Location.Y=262|Color=8388608|FontID=1|IsHidden=T|Text=-55°C to +125°C|Name=Temperature
|RECORD=41|OwnerIndex=432|IndexInSheet=16|OwnerPartId=-1|Location.X=279|Location.Y=262|Color=8388608|FontID=1|IsHidden=T|Text=TVS DIODE 14V 40V 0402|Name=Digikey Description
|RECORD=41|OwnerIndex=432|IndexInSheet=17|OwnerPartId=-1|Location.X=279|Location.Y=262|Color=8388608|FontID=1|IsHidden=T|Text=Yes|Name=Automotive
|RECORD=41|OwnerIndex=432|IndexInSheet=18|OwnerPartId=-1|Location.X=279|Location.Y=262|Color=8388608|FontID=1|IsHidden=T|Text=TVS Diodes|Name=Device Class L2
|RECORD=41|OwnerIndex=432|IndexInSheet=19|OwnerPartId=-1|Location.X=279|Location.Y=262|Color=8388608|FontID=1|IsHidden=T|Text=14V|Name=Reverse Standoff Voltage
|RECORD=41|OwnerIndex=432|IndexInSheet=20|OwnerPartId=-1|Location.X=279|Location.Y=262|Color=8388608|FontID=1|IsHidden=T|Text=Circuit Protection|Name=Device Class L1
|RECORD=41|OwnerIndex=432|IndexInSheet=21|OwnerPartId=-1|Location.X=279|Location.Y=262|Color=8388608|FontID=1|IsHidden=T|Text=DIOC10050X33|Name=Ipc Land Pattern Name
|RECORD=41|OwnerIndex=432|IndexInSheet=22|OwnerPartId=-1|Location.X=279|Location.Y=262|Color=8388608|FontID=1|IsHidden=T|Text=Grade 1|Name=Automotive Grade
|RECORD=41|OwnerIndex=432|IndexInSheet=23|OwnerPartId=-1|Location.X=279|Location.Y=262|Color=8388608|FontID=1|IsHidden=T|Text=PESD0402-140|Name=Manufacturer Part Number
|RECORD=41|OwnerIndex=432|IndexInSheet=24|OwnerPartId=-1|Location.X=279|Location.Y=262|Color=8388608|FontID=1|IsHidden=T|Text=14V|Name=Breakdown Voltage
|RECORD=41|OwnerIndex=432|IndexInSheet=25|OwnerPartId=-1|Location.X=279|Location.Y=262|Color=8388608|FontID=1|IsHidden=T|Text=0.25pF|Name=Capacitance
|RECORD=41|OwnerIndex=432|IndexInSheet=26|OwnerPartId=-1|Location.X=279|Location.Y=262|Color=8388608|FontID=1|IsHidden=T|Text=0.43mm|Name=Height
|RECORD=41|OwnerIndex=432|IndexInSheet=27|OwnerPartId=-1|Location.X=279|Location.Y=262|Color=8388608|FontID=1|IsHidden=T|Text=40V|Name=Clamping Voltage
|RECORD=41|OwnerIndex=432|IndexInSheet=28|OwnerPartId=-1|Location.X=279|Location.Y=262|Color=8388608|FontID=1|IsHidden=T|Text=0.25pF|Name=Value
|RECORD=41|OwnerIndex=432|IndexInSheet=29|OwnerPartId=-1|Location.X=279|Location.Y=262|Color=8388608|FontID=1|IsHidden=T|Text=TRUE|Name=RoHS
|RECORD=41|OwnerIndex=432|IndexInSheet=30|OwnerPartId=-1|Location.X=279|Location.Y=262|Color=8388608|FontID=1|IsHidden=T|Text=+125°C|Name=Temperature Range High
|RECORD=41|OwnerIndex=432|IndexInSheet=31|OwnerPartId=-1|Location.X=279|Location.Y=262|Color=8388608|FontID=1|IsHidden=T|Text=unset|Name=Device Class L3
|RECORD=41|OwnerIndex=432|IndexInSheet=32|OwnerPartId=-1|Location.X=279|Location.Y=262|Color=8388608|FontID=2|IsHidden=T|Text=https://octopart.com/pesd0402-140-littelfuse-74215061|Name=Octopart
|RECORD=41|OwnerIndex=432|IndexInSheet=33|OwnerPartId=-1|Location.X=279|Location.Y=262|Color=8388608|FontID=1|IsHidden=T|Text=PESD0402|Name=Package
|RECORD=41|OwnerIndex=432|IndexInSheet=34|OwnerPartId=-1|Location.X=279|Location.Y=262|Color=8388608|FontID=2|IsHidden=T|Text=https://www.littelfuse.com/~/media/electronics/datasheets/polymer_esd_suppressors/littelfuse_polymer_esd_suppressor_pesd_catalog_datasheet.pdf.pdf|Name=ComponentLink2URL
|RECORD=41|OwnerIndex=432|IndexInSheet=35|OwnerPartId=-1|Location.X=279|Location.Y=262|Color=8388608|FontID=1|IsHidden=T|Text=Bidirectional|Name=Direction
|RECORD=41|OwnerIndex=432|IndexInSheet=36|OwnerPartId=-1|Location.X=279|Location.Y=262|Color=8388608|FontID=1|IsHidden=T|Text=1|Name=Number Of Channels
|RECORD=41|OwnerIndex=432|IndexInSheet=37|OwnerPartId=-1|Location.X=279|Location.Y=262|Color=8388608|FontID=1|IsHidden=T|Text=Littelfuse Inc.|Name=Manufacturer
|RECORD=41|OwnerIndex=432|IndexInSheet=38|OwnerPartId=-1|Location.X=279|Location.Y=262|Color=8388608|FontID=1|IsHidden=T|Text=Diode|Name=Category
|RECORD=41|OwnerIndex=432|IndexInSheet=39|OwnerPartId=-1|Location.X=279|Location.Y=262|Color=8388608|FontID=1|IsHidden=T|Text=Datasheet|Name=ComponentLink2Description
|RECORD=34|OwnerIndex=432|IndexInSheet=-1|OwnerPartId=-1|Location.X=301|Location.Y=231|Color=8388608|FontID=1|Text=D1|Name=Designator|ReadOnlyState=1
|RECORD=41|OwnerIndex=432|IndexInSheet=-1|OwnerPartId=1|Location.X=301|Location.Y=221|Color=8388608|FontID=1|Text=PESD0402-140|Name=Comment
|RECORD=44|OwnerIndex=432
|RECORD=45|OwnerIndex=477|IndexInSheet=-1|UseComponentLibrary=T|ModelName=FP-PESD0402-MFG|ModelType=PCBLIB|DatafileCount=1|ModelDatafileEntity0=FP-PESD0402-MFG|ModelDatafileKind0=PCBLib|IsCurrent=T|DatalinksLocked=T|DatabaseDatalinksLocked=T
|RECORD=46|OwnerIndex=478
|RECORD=48|OwnerIndex=478
|RECORD=45|OwnerIndex=477|IndexInSheet=-1|UseComponentLibrary=T|ModelName=FP-PESD0402-IPC_C|ModelType=PCBLIB|DatafileCount=1|ModelDatafileEntity0=FP-PESD0402-IPC_C|ModelDatafileKind0=PCBLib|DatalinksLocked=T|DatabaseDatalinksLocked=T
|RECORD=46|OwnerIndex=481
|RECORD=48|OwnerIndex=481
|RECORD=45|OwnerIndex=477|IndexInSheet=-1|UseComponentLibrary=T|ModelName=FP-PESD0402-IPC_B|ModelType=PCBLIB|DatafileCount=1|ModelDatafileEntity0=FP-PESD0402-IPC_B|ModelDatafileKind0=PCBLib|DatalinksLocked=T|DatabaseDatalinksLocked=T
|RECORD=46|OwnerIndex=484
|RECORD=48|OwnerIndex=484
|RECORD=45|OwnerIndex=477|IndexInSheet=-1|UseComponentLibrary=T|ModelName=FP-PESD0402-IPC_A|ModelType=PCBLIB|DatafileCount=1|ModelDatafileEntity0=FP-PESD0402-IPC_A|ModelDatafileKind0=PCBLib|DatalinksLocked=T|DatabaseDatalinksLocked=T
|RECORD=46|OwnerIndex=487
|RECORD=48|OwnerIndex=487
|RECORD=1|LibReference=b4654b650e69147ec39a6b967a45e02|ComponentDescription=Chip Multilayer Ceramic Capacitors for General Purpose, 0201, 10000pF, X7R, 15%, 10%, 16V|PartCount=2|DisplayModeCount=1|IndexInSheet=41|OwnerPartId=-1|Location.X=400|Location.Y=270|CurrentPartId=1|LibraryPath=*|SourceLibraryName=Altium Content Vault|TargetFileName=*|AreaColor=11599871|Color=128|PartIDLocked=T|DesignItemId=CMP-06035-000448-1|AllPinCount=2
|RECORD=2|OwnerIndex=490|OwnerPartId=1|Electrical=4|PinConglomerate=33|PinLength=7|Location.X=400|Location.Y=263|Name=1|Designator=1|PinPropagationDelay=0.000000E+000
|RECORD=2|OwnerIndex=490|OwnerPartId=1|Electrical=4|PinConglomerate=35|PinLength=6|Location.X=400|Location.Y=256|Name=2|Designator=2|PinPropagationDelay=0.000000E+000
|RECORD=13|OwnerIndex=490|IsNotAccesible=T|IndexInSheet=2|OwnerPartId=1|Location.X=410|Location.Y=263|Corner.X=390|Corner.Y=263|LineWidth=1|Color=16711680
|RECORD=13|OwnerIndex=490|IsNotAccesible=T|IndexInSheet=3|OwnerPartId=1|Location.X=410|Location.Y=257|Corner.X=390|Corner.Y=257|LineWidth=1|Color=16711680
|RECORD=13|OwnerIndex=490|IsNotAccesible=T|IndexInSheet=4|OwnerPartId=1|Location.X=400|Location.Y=263|Corner.X=400|Corner.Y=266|LineWidth=1|Color=16711680
|RECORD=13|OwnerIndex=490|IsNotAccesible=T|IndexInSheet=5|OwnerPartId=1|Location.X=400|Location.Y=256|Corner.X=400|Corner.Y=255|LineWidth=1|Color=16711680
|RECORD=41|OwnerIndex=490|IndexInSheet=6|OwnerPartId=-1|Location.X=389|Location.Y=272|Color=8388608|FontID=1|IsHidden=T|Text=300um|Name=Width
|RECORD=41|OwnerIndex=490|IndexInSheet=7|OwnerPartId=-1|Location.X=389|Location.Y=272|Color=8388608|FontID=1|IsHidden=T|Text=10%|Name=Tolerance
|RECORD=41|OwnerIndex=490|IndexInSheet=8|OwnerPartId=-1|Location.X=389|Location.Y=272|Color=8388608|FontID=1|IsHidden=T|Text=10nF|Name=Capacitance
|RECORD=41|OwnerIndex=490|IndexInSheet=9|OwnerPartId=-1|Location.X=389|Location.Y=272|Color=8388608|FontID=1|IsHidden=T|Text=300um|Name=Thickness
|RECORD=41|OwnerIndex=490|IndexInSheet=10|OwnerPartId=-1|Location.X=389|Location.Y=272|Color=8388608|FontID=1|IsHidden=T|Text=X7R|Name=Dielectric
|RECORD=41|OwnerIndex=490|IndexInSheet=11|OwnerPartId=-1|Location.X=389|Location.Y=272|Color=8388608|FontID=1|IsHidden=T|Text=16V|Name=Voltage Rating (DC)
|RECORD=41|OwnerIndex=490|IndexInSheet=12|OwnerPartId=-1|Location.X=389|Location.Y=272|Color=8388608|FontID=1|IsHidden=T|Text=600um|Name=Length
|RECORD=34|OwnerIndex=490|IndexInSheet=-1|OwnerPartId=-1|Location.X=411|Location.Y=257|Color=8388608|FontID=1|Text=C10|Name=Designator|ReadOnlyState=1
|RECORD=41|OwnerIndex=490|IndexInSheet=-1|OwnerPartId=1|Location.X=411|Location.Y=247|Color=8388608|FontID=1|Text=10nF|Name=Comment
|RECORD=44|OwnerIndex=490
|RECORD=45|OwnerIndex=508|IndexInSheet=-1|UseComponentLibrary=T|ModelName=FP-GRM033-0_03-IPC_B|ModelType=PCBLIB|DatafileCount=1|ModelDatafileEntity0=FP-GRM033-0_03-IPC_B|ModelDatafileKind0=PCBLib|IsCurrent=T|DatalinksLocked=T|DatabaseDatalinksLocked=T
|RECORD=46|OwnerIndex=509
|RECORD=48|OwnerIndex=509
|RECORD=45|OwnerIndex=508|IndexInSheet=-1|UseComponentLibrary=T|ModelName=FP-GRM033-0_03-IPC_A|ModelType=PCBLIB|DatafileCount=1|ModelDatafileEntity0=FP-GRM033-0_03-IPC_A|ModelDatafileKind0=PCBLib|DatalinksLocked=T|DatabaseDatalinksLocked=T
|RECORD=46|OwnerIndex=512
|RECORD=48|OwnerIndex=512
|RECORD=45|OwnerIndex=508|IndexInSheet=-1|UseComponentLibrary=T|ModelName=FP-GRM033-0_03-MFG|ModelType=PCBLIB|DatafileCount=1|ModelDatafileEntity0=FP-GRM033-0_03-MFG|ModelDatafileKind0=PCBLib|DatalinksLocked=T|DatabaseDatalinksLocked=T
|RECORD=46|OwnerIndex=515
|RECORD=48|OwnerIndex=515
|RECORD=45|OwnerIndex=508|IndexInSheet=-1|UseComponentLibrary=T|ModelName=FP-GRM033-0_03-IPC_C|ModelType=PCBLIB|DatafileCount=1|ModelDatafileEntity0=FP-GRM033-0_03-IPC_C|ModelDatafileKind0=PCBLib|DatalinksLocked=T|DatabaseDatalinksLocked=T
|RECORD=46|OwnerIndex=518
|RECORD=48|OwnerIndex=518
|RECORD=17|IndexInSheet=42|OwnerPartId=-1|Style=4|ShowNetName=F|Location.X=540|Location.Y=370|Orientation=3|Color=128|FontID=1|Text=GND
|RECORD=17|IndexInSheet=43|OwnerPartId=-1|Style=2|ShowNetName=T|Location.X=540|Location.Y=480|Orientation=1|Color=128|FontID=1|Text=VCC
|RECORD=1|LibReference=b4654b650e69147ec39a6b967a45e02|ComponentDescription=None|PartCount=2|DisplayModeCount=1|IndexInSheet=44|OwnerPartId=-1|Location.X=560|Location.Y=480|CurrentPartId=1|LibraryPath=*|SourceLibraryName=Altium Content Vault|TargetFileName=*|AreaColor=11599871|Color=128|PartIDLocked=T|DesignItemId=CMP-14477-000330-2|AllPinCount=2
|RECORD=2|OwnerIndex=523|OwnerPartId=1|Electrical=4|PinConglomerate=33|PinLength=7|Location.X=560|Location.Y=473|Name=1|Designator=1|PinPropagationDelay=0.000000E+000
|RECORD=2|OwnerIndex=523|OwnerPartId=1|Electrical=4|PinConglomerate=35|PinLength=6|Location.X=560|Location.Y=466|Name=2|Designator=2|PinPropagationDelay=0.000000E+000
|RECORD=13|OwnerIndex=523|IsNotAccesible=T|IndexInSheet=2|OwnerPartId=1|Location.X=570|Location.Y=473|Corner.X=550|Corner.Y=473|LineWidth=1|Color=16711680
|RECORD=13|OwnerIndex=523|IsNotAccesible=T|IndexInSheet=3|OwnerPartId=1|Location.X=570|Location.Y=467|Corner.X=550|Corner.Y=467|LineWidth=1|Color=16711680
|RECORD=13|OwnerIndex=523|IsNotAccesible=T|IndexInSheet=4|OwnerPartId=1|Location.X=560|Location.Y=473|Corner.X=560|Corner.Y=476|LineWidth=1|Color=16711680
|RECORD=13|OwnerIndex=523|IsNotAccesible=T|IndexInSheet=5|OwnerPartId=1|Location.X=560|Location.Y=466|Corner.X=560|Corner.Y=465|LineWidth=1|Color=16711680
|RECORD=41|OwnerIndex=523|IndexInSheet=6|OwnerPartId=-1|Location.X=549|Location.Y=482|Color=8388608|FontID=1|IsHidden=T|Text=Yes|Name=RoHS Compliant
|RECORD=41|OwnerIndex=523|IndexInSheet=7|OwnerPartId=-1|Location.X=549|Location.Y=482|Color=8388608|FontID=1|IsHidden=T|Text=SMD/SMT|Name=Termination
|RECORD=41|OwnerIndex=523|IndexInSheet=8|OwnerPartId=-1|Location.X=549|Location.Y=482|Color=8388608|FontID=1|IsHidden=T|Text=Tape and Reel|Name=Packaging
|RECORD=41|OwnerIndex=523|IndexInSheet=9|OwnerPartId=-1|Location.X=549|Location.Y=482|Color=8388608|FontID=1|IsHidden=T|Text=50V|Name=Voltage Rating (DC)
|RECORD=41|OwnerIndex=523|IndexInSheet=10|OwnerPartId=-1|Location.X=549|Location.Y=482|Color=8388608|FontID=1|IsHidden=T|Text=100nF|Name=Capacitance
|RECORD=41|OwnerIndex=523|IndexInSheet=11|OwnerPartId=-1|Location.X=549|Location.Y=482|Color=8388608|FontID=1|IsHidden=T|Text=0.5mm|Name=Height
|RECORD=41|OwnerIndex=523|IndexInSheet=12|OwnerPartId=-1|Location.X=549|Location.Y=482|Color=8388608|FontID=1|IsHidden=T|Text=Halogen Free|Name=Halogen Free
|RECORD=41|OwnerIndex=523|IndexInSheet=13|OwnerPartId=-1|Location.X=549|Location.Y=482|Color=8388608|FontID=1|IsHidden=T|Text=1005|Name=Case Code (Metric)
|RECORD=41|OwnerIndex=523|IndexInSheet=14|OwnerPartId=-1|Location.X=549|Location.Y=482|Color=8388608|FontID=1|IsHidden=T|Text=0.02inch|Name=Width
|RECORD=41|OwnerIndex=523|IndexInSheet=15|OwnerPartId=-1|Location.X=549|Location.Y=482|Color=8388608|FontID=1|IsHidden=T|Text=85°C|Name=Max Operating Temperature
|RECORD=41|OwnerIndex=523|IndexInSheet=16|OwnerPartId=-1|Location.X=549|Location.Y=482|Color=8388608|FontID=1|IsHidden=T|Text=50V|Name=Voltage Rating
|RECORD=41|OwnerIndex=523|IndexInSheet=17|OwnerPartId=-1|Location.X=549|Location.Y=482|Color=8388608|FontID=1|IsHidden=T|Text=-55°C|Name=Min Operating Temperature
|RECORD=41|OwnerIndex=523|IndexInSheet=18|OwnerPartId=-1|Location.X=549|Location.Y=482|Color=8388608|FontID=1|IsHidden=T|Text=10000|Name=Package Quantity
|RECORD=41|OwnerIndex=523|IndexInSheet=19|OwnerPartId=-1|Location.X=549|Location.Y=482|Color=8388608|FontID=1|IsHidden=T|Text=0402|Name=Case/Package
|RECORD=41|OwnerIndex=523|IndexInSheet=20|OwnerPartId=-1|Location.X=549|Location.Y=482|Color=8388608|FontID=1|IsHidden=T|Text=0402|Name=Case Code (Imperial)
|RECORD=41|OwnerIndex=523|IndexInSheet=21|OwnerPartId=-1|Location.X=549|Location.Y=482|Color=8388608|FontID=1|IsHidden=T|Text=X5R|Name=Dielectric
|RECORD=41|OwnerIndex=523|IndexInSheet=22|OwnerPartId=-1|Location.X=549|Location.Y=482|Color=8388608|FontID=1|IsHidden=T|Text=10%|Name=Tolerance
|RECORD=41|OwnerIndex=523|IndexInSheet=23|OwnerPartId=-1|Location.X=549|Location.Y=482|Color=8388608|FontID=1|IsHidden=T|Text=0.039inch|Name=Length
|RECORD=41|OwnerIndex=523|IndexInSheet=24|OwnerPartId=-1|Location.X=549|Location.Y=482|Color=8388608|FontID=1|IsHidden=T|Text=0.022inch|Name=Thickness
|RECORD=41|OwnerIndex=523|IndexInSheet=25|OwnerPartId=-1|Location.X=549|Location.Y=482|Color=8388608|FontID=1|IsHidden=T|Text=Surface Mount|Name=Mount
|RECORD=34|OwnerIndex=523|IndexInSheet=-1|OwnerPartId=-1|Location.X=571|Location.Y=467|Color=8388608|FontID=1|Text=C7|Name=Designator|ReadOnlyState=1
|RECORD=41|OwnerIndex=523|IndexInSheet=-1|OwnerPartId=1|Location.X=571|Location.Y=457|Color=8388608|FontID=1|Text=100nF|Name=Comment
|RECORD=44|OwnerIndex=523
|RECORD=45|OwnerIndex=554|IndexInSheet=-1|UseComponentLibrary=T|ModelName=FP-0402-L_1_0_0_05-W_0_5-IPC_B|ModelType=PCBLIB|DatafileCount=1|ModelDatafileEntity0=FP-0402-L_1_0_0_05-W_0_5-IPC_B|ModelDatafileKind0=PCBLib|IsCurrent=T|DatalinksLocked=T|DatabaseDatalinksLocked=T
|RECORD=46|OwnerIndex=555
|RECORD=48|OwnerIndex=555
|RECORD=45|OwnerIndex=554|IndexInSheet=-1|UseComponentLibrary=T|ModelName=FP-0402-L_1_0_0_05-W_0_5-IPC_A|ModelType=PCBLIB|DatafileCount=1|ModelDatafileEntity0=FP-0402-L_1_0_0_05-W_0_5-IPC_A|ModelDatafileKind0=PCBLib|DatalinksLocked=T|DatabaseDatalinksLocked=T
|RECORD=46|OwnerIndex=558
|RECORD=48|OwnerIndex=558
|RECORD=45|OwnerIndex=554|IndexInSheet=-1|UseComponentLibrary=T|ModelName=FP-0402-L_1_0_0_05-W_0_5-MFG|ModelType=PCBLIB|DatafileCount=1|ModelDatafileEntity0=FP-0402-L_1_0_0_05-W_0_5-MFG|ModelDatafileKind0=PCBLib|DatalinksLocked=T|DatabaseDatalinksLocked=T
|RECORD=46|OwnerIndex=561
|RECORD=48|OwnerIndex=561
|RECORD=45|OwnerIndex=554|IndexInSheet=-1|UseComponentLibrary=T|ModelName=UMK105BJ104_V-F|ModelType=SIM|IsCurrent=T|DatalinksLocked=T|DatabaseDatalinksLocked=T
|RECORD=46|OwnerIndex=564
|RECORD=48|OwnerIndex=564
|RECORD=41|OwnerIndex=566|IndexInSheet=-1|OwnerPartId=-1|Color=8388608|FontID=1|IsHidden=T|Text=General|Name=Kind
|RECORD=41|OwnerIndex=566|IndexInSheet=-1|OwnerPartId=-1|Color=8388608|FontID=1|IsHidden=T|Text=Spice Subcircuit|Name=SubKind
|RECORD=41|OwnerIndex=566|IndexInSheet=-1|OwnerPartId=-1|Color=8388608|FontID=1|IsHidden=T|Name=Spice Prefix
|RECORD=41|OwnerIndex=566|IndexInSheet=-1|OwnerPartId=-1|Color=8388608|FontID=1|IsHidden=T|Name=Excluded Parts
|RECORD=41|OwnerIndex=566|IndexInSheet=-1|OwnerPartId=-1|Color=8388608|FontID=1|IsHidden=T|Name=Netlist
|RECORD=41|OwnerIndex=566|IndexInSheet=-1|OwnerPartId=-1|Color=8388608|FontID=1|IsHidden=T|Text=document_sim_cache\PIVZSDOR\0|Name=SimulationCacheLocation|ReadOnlyState=3
|RECORD=45|OwnerIndex=554|IndexInSheet=-1|UseComponentLibrary=T|ModelName=FP-0402-L_1_0_0_05-W_0_5-IPC_C|ModelType=PCBLIB|DatafileCount=1|ModelDatafileEntity0=FP-0402-L_1_0_0_05-W_0_5-IPC_C|ModelDatafileKind0=PCBLib|DatalinksLocked=T|DatabaseDatalinksLocked=T
|RECORD=46|OwnerIndex=573
|RECORD=48|OwnerIndex=573
|RECORD=41|IndexInSheet=45|OwnerPartId=-1|Color=8388608|FontID=1|IsHidden=T|Text=|Name=SPICEModelCachePIVZSDOR|ReadOnlyState=3
|RECORD=17|IndexInSheet=46|OwnerPartId=-1|Style=4|ShowNetName=F|Location.X=560|Location.Y=460|Orientation=3|Color=128|FontID=1|Text=GND
|RECORD=17|IndexInSheet=47|OwnerPartId=-1|Style=4|ShowNetName=F|Location.X=460|Location.Y=320|Orientation=3|Color=128|FontID=1|Text=GND
|RECORD=17|IndexInSheet=48|OwnerPartId=-1|Style=4|ShowNetName=F|Location.X=400|Location.Y=250|Orientation=3|Color=128|FontID=1|Text=GND
|RECORD=1|LibReference=1029c3af85768c4190bb7ad29bc67b5|ComponentDescription=100kO ±1% 0.063W 0402 Thick Film Chip Resistor AEC-Q200 compliant|PartCount=2|DisplayModeCount=1|IndexInSheet=49|OwnerPartId=-1|Location.X=600|Location.Y=600|Orientation=1|CurrentPartId=1|LibraryPath=*|SourceLibraryName=Altium Content Vault|TargetFileName=*|AreaColor=11599871|Color=128|PartIDLocked=T|DesignItemId=CMP-2000-06984-2|AllPinCount=2
|RECORD=2|OwnerIndex=580|OwnerPartId=1|Electrical=4|PinConglomerate=35|PinLength=20|Location.X=600|Location.Y=620|Name=1|Designator=1|PinPropagationDelay=0.000000E+000
|RECORD=2|OwnerIndex=580|OwnerPartId=1|Electrical=4|PinConglomerate=33|PinLength=20|Location.X=600|Location.Y=650|Name=2|Designator=2|PinPropagationDelay=0.000000E+000
|RECORD=13|OwnerIndex=580|IsNotAccesible=T|IndexInSheet=2|OwnerPartId=1|Location.X=600|Location.Y=620|Corner.X=595|Corner.Y=623|LineWidth=1|Color=16711680
|RECORD=13|OwnerIndex=580|IsNotAccesible=T|IndexInSheet=3|OwnerPartId=1|Location.X=595|Location.Y=623|Corner.X=605|Corner.Y=628|LineWidth=1|Color=16711680
|RECORD=13|OwnerIndex=580|IsNotAccesible=T|IndexInSheet=4|OwnerPartId=1|Location.X=605|Location.Y=628|Corner.X=595|Corner.Y=633|LineWidth=1|Color=16711680
|RECORD=13|OwnerIndex=580|IsNotAccesible=T|IndexInSheet=5|OwnerPartId=1|Location.X=595|Location.Y=633|Corner.X=605|Corner.Y=638|LineWidth=1|Color=16711680
|RECORD=13|OwnerIndex=580|IsNotAccesible=T|IndexInSheet=6|OwnerPartId=1|Location.X=605|Location.Y=638|Corner.X=595|Corner.Y=643|LineWidth=1|Color=16711680
|RECORD=13|OwnerIndex=580|IsNotAccesible=T|IndexInSheet=7|OwnerPartId=1|Location.X=595|Location.Y=643|Corner.X=605|Corner.Y=648|LineWidth=1|Color=16711680
|RECORD=13|OwnerIndex=580|IsNotAccesible=T|IndexInSheet=8|OwnerPartId=1|Location.X=605|Location.Y=648|Corner.X=600|Corner.Y=650|LineWidth=1|Color=16711680
|RECORD=13|OwnerIndex=580|IsNotAccesible=T|IndexInSheet=9|OwnerPartId=1|Location.X=600|Location.Y=620|Corner.X=600|Corner.Y=617|LineWidth=1|Color=16711680
|RECORD=13|OwnerIndex=580|IsNotAccesible=T|IndexInSheet=10|OwnerPartId=1|Location.X=600|Location.Y=650|Corner.X=600|Corner.Y=653|LineWidth=1|Color=16711680
|RECORD=41|OwnerIndex=580|IndexInSheet=11|OwnerPartId=-1|Location.X=594|Location.Y=672|Color=8388608|FontID=1|IsHidden=T|Text=63mW|Name=Max Power Dissipation
|RECORD=41|OwnerIndex=580|IndexInSheet=12|OwnerPartId=-1|Location.X=594|Location.Y=672|Color=8388608|FontID=1|IsHidden=T|Text=Tape and Reel|Name=Packaging
|RECORD=41|OwnerIndex=580|IndexInSheet=13|OwnerPartId=-1|Location.X=594|Location.Y=672|Color=8388608|FontID=1|IsHidden=T|Text=0402|Name=Size Code
|RECORD=41|OwnerIndex=580|IndexInSheet=14|OwnerPartId=-1|Location.X=594|Location.Y=672|Color=8388608|FontID=1|IsHidden=T|Text=100kR|Name=Resistance
|RECORD=41|OwnerIndex=580|IndexInSheet=15|OwnerPartId=-1|Location.X=594|Location.Y=672|Color=8388608|FontID=1|IsHidden=T|Text=Thick Film|Name=Resistor Type
|RECORD=41|OwnerIndex=580|IndexInSheet=16|OwnerPartId=-1|Location.X=594|Location.Y=672|Color=8388608|FontID=1|IsHidden=T|Text=Automotive AEC-Q200|Name=Features
|RECORD=41|OwnerIndex=580|IndexInSheet=17|OwnerPartId=-1|Location.X=594|Location.Y=672|Color=8388608|FontID=1|IsHidden=T|Text=100ppm/°C|Name=Temperature Coefficient
|RECORD=41|OwnerIndex=580|IndexInSheet=18|OwnerPartId=-1|Location.X=594|Location.Y=672|Color=8388608|FontID=1|IsHidden=T|Text=1005|Name=Case Code (Metric)
|RECORD=41|OwnerIndex=580|IndexInSheet=19|OwnerPartId=-1|Location.X=594|Location.Y=672|Color=8388608|FontID=1|IsHidden=T|Text=Yes|Name=RoHS Compliant
|RECORD=41|OwnerIndex=580|IndexInSheet=20|OwnerPartId=-1|Location.X=594|Location.Y=672|Color=8388608|FontID=1|IsHidden=T|Text=1mm|Name=Length
|RECORD=41|OwnerIndex=580|IndexInSheet=21|OwnerPartId=-1|Location.X=594|Location.Y=672|Color=8388608|FontID=1|IsHidden=T|Text=No|Name=Radiation Hardening
|RECORD=41|OwnerIndex=580|IndexInSheet=22|OwnerPartId=-1|Location.X=594|Location.Y=672|Color=8388608|FontID=1|IsHidden=T|Text=Not|Name=Military Standard
|RECORD=41|OwnerIndex=580|IndexInSheet=23|OwnerPartId=-1|Location.X=594|Location.Y=672|Color=8388608|FontID=1|IsHidden=T|Text=0402|Name=Case Code (Imperial)
|RECORD=41|OwnerIndex=580|IndexInSheet=24|OwnerPartId=-1|Location.X=594|Location.Y=672|Color=8388608|FontID=1|IsHidden=T|Text=0.5mm|Name=Depth
|RECORD=41|OwnerIndex=580|IndexInSheet=25|OwnerPartId=-1|Location.X=594|Location.Y=672|Color=8388608|FontID=1|IsHidden=T|Text=155°C|Name=Max Operating Temperature
|RECORD=41|OwnerIndex=580|IndexInSheet=26|OwnerPartId=-1|Location.X=594|Location.Y=672|Color=8388608|FontID=1|IsHidden=T|Text=Lead Free|Name=Lead Free
|RECORD=41|OwnerIndex=580|IndexInSheet=27|OwnerPartId=-1|Location.X=594|Location.Y=672|Color=8388608|FontID=1|IsHidden=T|Text=0402|Name=Case/Package
|RECORD=41|OwnerIndex=580|IndexInSheet=28|OwnerPartId=-1|Location.X=594|Location.Y=672|Color=8388608|FontID=1|IsHidden=T|Text=1%|Name=Tolerance
|RECORD=41|OwnerIndex=580|IndexInSheet=29|OwnerPartId=-1|Location.X=594|Location.Y=672|Color=8388608|FontID=1|IsHidden=T|Text=Rectangular|Name=Construction
|RECORD=41|OwnerIndex=580|IndexInSheet=30|OwnerPartId=-1|Location.X=594|Location.Y=672|Color=8388608|FontID=1|IsHidden=T|Text=2|Name=Number of Terminations
|RECORD=41|OwnerIndex=580|IndexInSheet=31|OwnerPartId=-1|Location.X=594|Location.Y=672|Color=8388608|FontID=1|IsHidden=T|Text=Surface Mount|Name=Mount
|RECORD=41|OwnerIndex=580|IndexInSheet=32|OwnerPartId=-1|Location.X=594|Location.Y=672|Color=8388608|FontID=1|IsHidden=T|Text=-55°C|Name=Min Operating Temperature
|RECORD=41|OwnerIndex=580|IndexInSheet=33|OwnerPartId=-1|Location.X=594|Location.Y=672|Color=8388608|FontID=1|IsHidden=T|Text=0.02inch|Name=Width
|RECORD=41|OwnerIndex=580|IndexInSheet=34|OwnerPartId=-1|Location.X=594|Location.Y=672|Color=8388608|FontID=1|IsHidden=T|Text=RMCF|Name=Series
|RECORD=41|OwnerIndex=580|IndexInSheet=35|OwnerPartId=-1|Location.X=594|Location.Y=672|Color=8388608|FontID=1|IsHidden=T|Text=Tin|Name=Contact Plating
|RECORD=41|OwnerIndex=580|IndexInSheet=36|OwnerPartId=-1|Location.X=594|Location.Y=672|Color=8388608|FontID=1|IsHidden=T|Text=62.5mW|Name=Power Rating
|RECORD=41|OwnerIndex=580|IndexInSheet=37|OwnerPartId=-1|Location.X=594|Location.Y=672|Color=8388608|FontID=1|IsHidden=T|Text=0.016inch|Name=Height
|RECORD=34|OwnerIndex=580|IndexInSheet=-1|OwnerPartId=-1|Location.X=606|Location.Y=644|Color=8388608|FontID=1|Text=R9|Name=Designator|ReadOnlyState=1
|RECORD=41|OwnerIndex=580|IndexInSheet=-1|OwnerPartId=1|Location.X=606|Location.Y=634|Color=8388608|FontID=1|Text=100k|Name=Comment
|RECORD=44|OwnerIndex=580
|RECORD=45|OwnerIndex=623|IndexInSheet=-1|UseComponentLibrary=T|ModelName=FP-RMCF0402-IPC_C|ModelType=PCBLIB|DatafileCount=1|ModelDatafileEntity0=FP-RMCF0402-IPC_C|ModelDatafileKind0=PCBLib|IsCurrent=T|DatalinksLocked=T|DatabaseDatalinksLocked=T
|RECORD=46|OwnerIndex=624
|RECORD=48|OwnerIndex=624
|RECORD=45|OwnerIndex=623|IndexInSheet=-1|UseComponentLibrary=T|ModelName=FP-RMCF0402-IPC_A|ModelType=PCBLIB|DatafileCount=1|ModelDatafileEntity0=FP-RMCF0402-IPC_A|ModelDatafileKind0=PCBLib|DatalinksLocked=T|DatabaseDatalinksLocked=T
|RECORD=46|OwnerIndex=627
|RECORD=48|OwnerIndex=627
|RECORD=45|OwnerIndex=623|IndexInSheet=-1|UseComponentLibrary=T|ModelName=FP-RMCF0402-IPC_B|ModelType=PCBLIB|DatafileCount=1|ModelDatafileEntity0=FP-RMCF0402-IPC_B|ModelDatafileKind0=PCBLib|DatalinksLocked=T|DatabaseDatalinksLocked=T
|RECORD=46|OwnerIndex=630
|RECORD=48|OwnerIndex=630
|RECORD=45|OwnerIndex=623|IndexInSheet=-1|UseComponentLibrary=T|ModelName=FP-RMCF0402-MFG|ModelType=PCBLIB|DatafileCount=1|ModelDatafileEntity0=FP-RMCF0402-MFG|ModelDatafileKind0=PCBLib|DatalinksLocked=T|DatabaseDatalinksLocked=T
|RECORD=46|OwnerIndex=633
|RECORD=48|OwnerIndex=633
|RECORD=17|IndexInSheet=50|OwnerPartId=-1|Style=2|ShowNetName=T|Location.X=660|Location.Y=680|Orientation=1|Color=128|FontID=1|Text=VCC_ANT
|RECORD=17|IndexInSheet=51|OwnerPartId=-1|Style=4|ShowNetName=F|Location.X=290|Location.Y=160|Orientation=3|Color=128|FontID=1|Text=GND
|RECORD=1|LibReference=TI-SN74XXX3G0X-XX-8|ComponentDescription=Triple Buffer/Driver With Open-Drain Output, DCU0008A, LARGE T&R|PartCount=5|DisplayModeCount=1|IndexInSheet=52|OwnerPartId=-1|Location.X=750|Location.Y=290|CurrentPartId=4|LibraryPath=*|SourceLibraryName=Altium Content Vault|TargetFileName=*|AreaColor=11599871|Color=128|PartIDLocked=F|DesignItemId=CMP-0859-00615-3|AllPinCount=8
|RECORD=2|OwnerIndex=638|OwnerPartId=3|FormalType=1|Electrical=3|PinConglomerate=48|PinLength=20|Location.X=780|Location.Y=270|Name=3Y|Designator=2|SwapIDPart=Ž&Ž2|PinPropagationDelay=0.000000E+000
|RECORD=2|OwnerIndex=638|OwnerPartId=3|FormalType=1|PinConglomerate=50|PinLength=20|Location.X=750|Location.Y=270|Name=3A|Designator=6|SwapIDPart=Ž&Ž2|PinPropagationDelay=0.000000E+000
|RECORD=13|OwnerIndex=638|IsNotAccesible=T|IndexInSheet=2|OwnerPartId=3|Location.X=750|Location.Y=285|Corner.X=780|Corner.Y=270|LineWidth=1|Color=16711680
|RECORD=13|OwnerIndex=638|IsNotAccesible=T|IndexInSheet=3|OwnerPartId=3|Location.X=750|Location.Y=255|Corner.X=780|Corner.Y=270|LineWidth=1|Color=16711680
|RECORD=13|OwnerIndex=638|IsNotAccesible=T|IndexInSheet=4|OwnerPartId=3|Location.X=750|Location.Y=255|Corner.X=750|Corner.Y=285|LineWidth=1|Color=16711680
|RECORD=2|OwnerIndex=638|OwnerPartId=2|FormalType=1|Electrical=3|PinConglomerate=48|PinLength=20|Location.X=780|Location.Y=270|Name=2Y|Designator=5|SwapIDPart=Ž&Ž2|PinPropagationDelay=0.000000E+000
|RECORD=2|OwnerIndex=638|OwnerPartId=2|FormalType=1|PinConglomerate=50|PinLength=20|Location.X=750|Location.Y=270|Name=2A|Designator=3|SwapIDPart=Ž&Ž2|PinPropagationDelay=0.000000E+000
|RECORD=13|OwnerIndex=638|IsNotAccesible=T|IndexInSheet=7|OwnerPartId=2|Location.X=750|Location.Y=285|Corner.X=780|Corner.Y=270|LineWidth=1|Color=16711680
|RECORD=13|OwnerIndex=638|IsNotAccesible=T|IndexInSheet=8|OwnerPartId=2|Location.X=750|Location.Y=255|Corner.X=780|Corner.Y=270|LineWidth=1|Color=16711680
|RECORD=13|OwnerIndex=638|IsNotAccesible=T|IndexInSheet=9|OwnerPartId=2|Location.X=750|Location.Y=255|Corner.X=750|Corner.Y=285|LineWidth=1|Color=16711680
|RECORD=14|OwnerIndex=638|IsNotAccesible=T|IndexInSheet=10|OwnerPartId=4|Location.X=750|Location.Y=270|Corner.X=810|Corner.Y=290|Color=128|AreaColor=11599871|IsSolid=T
|RECORD=2|OwnerIndex=638|OwnerPartId=4|FormalType=1|Electrical=7|PinConglomerate=56|PinLength=20|Location.X=810|Location.Y=280|Name=GND|Designator=4|PinPropagationDelay=0.000000E+000
|RECORD=2|OwnerIndex=638|OwnerPartId=4|FormalType=1|Electrical=7|PinConglomerate=58|PinLength=20|Location.X=750|Location.Y=280|Name=VCC|Designator=8|PinPropagationDelay=0.000000E+000
|RECORD=2|OwnerIndex=638|OwnerPartId=1|FormalType=1|Electrical=3|PinConglomerate=48|PinLength=20|Location.X=780|Location.Y=270|Name=1Y|Designator=7|SwapIDPart=Ž&Ž2|PinPropagationDelay=0.000000E+000
|RECORD=2|OwnerIndex=638|OwnerPartId=1|FormalType=1|PinConglomerate=50|PinLength=20|Location.X=750|Location.Y=270|Name=1A|Designator=1|SwapIDPart=Ž&Ž2|PinPropagationDelay=0.000000E+000
|RECORD=13|OwnerIndex=638|IsNotAccesible=T|IndexInSheet=15|OwnerPartId=1|Location.X=750|Location.Y=285|Corner.X=780|Corner.Y=270|LineWidth=1|Color=16711680
|RECORD=13|OwnerIndex=638|IsNotAccesible=T|IndexInSheet=16|OwnerPartId=1|Location.X=750|Location.Y=255|Corner.X=780|Corner.Y=270|LineWidth=1|Color=16711680
|RECORD=13|OwnerIndex=638|IsNotAccesible=T|IndexInSheet=17|OwnerPartId=1|Location.X=750|Location.Y=255|Corner.X=750|Corner.Y=285|LineWidth=1|Color=16711680
|RECORD=41|OwnerIndex=638|IndexInSheet=18|OwnerPartId=-1|Location.X=728|Location.Y=305|Color=8388608|FontID=1|IsHidden=T|Text=SN74LVC3G07|Name=Generic Part Number
|RECORD=41|OwnerIndex=638|IndexInSheet=19|OwnerPartId=-1|Location.X=728|Location.Y=305|Color=8388608|FontID=1|IsHidden=T|Text=5.5|Name=VCC(Max)(V)
|RECORD=41|OwnerIndex=638|IndexInSheet=20|OwnerPartId=-1|Location.X=728|Location.Y=305|Color=8388608|FontID=1|IsHidden=T|Text=Non-Inverting Buffer/Driver|Name=Sub-Family
|RECORD=41|OwnerIndex=638|IndexInSheet=21|OwnerPartId=-1|Location.X=728|Location.Y=305|Color=8388608|FontID=1|IsHidden=T|Text=True|Name=Logic
|RECORD=41|OwnerIndex=638|IndexInSheet=22|OwnerPartId=-1|Location.X=728|Location.Y=305|Color=8388608|FontID=1|IsHidden=T|Text=DCU0008A|Name=PackageReference
|RECORD=41|OwnerIndex=638|IndexInSheet=23|OwnerPartId=-1|Location.X=728|Location.Y=305|Color=8388608|FontID=1|IsHidden=T|Text=8.3,4.8,4.2,3.4|Name=tpd @ Nom Voltage(Max)(ns)
|RECORD=41|OwnerIndex=638|IndexInSheet=24|OwnerPartId=-1|Location.X=728|Location.Y=305|Color=8388608|FontID=1|IsHidden=T|Text=CMOS|Name=Output Type
|RECORD=41|OwnerIndex=638|IndexInSheet=25|OwnerPartId=-1|Location.X=728|Location.Y=305|Color=8388608|FontID=1|IsHidden=T|Text=150|Name=F @ Nom Voltage(Max)(Mhz)
|RECORD=41|OwnerIndex=638|IndexInSheet=26|OwnerPartId=-1|Location.X=728|Location.Y=305|Color=8388608|FontID=1|IsHidden=T|Text=LVC|Name=Technology Family
|RECORD=41|OwnerIndex=638|IndexInSheet=27|OwnerPartId=-1|Location.X=728|Location.Y=305|Color=8388608|FontID=1|IsHidden=T|Text=0.01|Name=ICC @ Nom Voltage(Max)(mA)
|RECORD=41|OwnerIndex=638|IndexInSheet=28|OwnerPartId=-1|Location.X=728|Location.Y=305|Color=8388608|FontID=1|IsHidden=T|Text=1.8,2.5,3.3,5|Name=Voltage(Nom)(V)
|RECORD=41|OwnerIndex=638|IndexInSheet=29|OwnerPartId=-1|Location.X=728|Location.Y=305|Color=8388608|FontID=1|IsHidden=T|Text=No|Name=Schmitt Trigger
|RECORD=41|OwnerIndex=638|IndexInSheet=30|OwnerPartId=-1|Location.X=728|Location.Y=305|Color=8388608|FontID=1|IsHidden=T|Text=Texas Instruments|Name=Manufacturer
|RECORD=41|OwnerIndex=638|IndexInSheet=31|OwnerPartId=-1|Location.X=728|Location.Y=305|Color=8388608|FontID=1|IsHidden=T|Text=1.65|Name=VCC(Min)(V)
|RECORD=41|OwnerIndex=638|IndexInSheet=32|OwnerPartId=-1|Location.X=728|Location.Y=305|Color=8388608|FontID=1|IsHidden=T|Text=No|Name=3-State Output
|RECORD=41|OwnerIndex=638|IndexInSheet=33|OwnerPartId=-1|Location.X=728|Location.Y=305|Color=8388608|FontID=1|IsHidden=T|Text=3|Name=Bits(#)
|RECORD=41|OwnerIndex=638|IndexInSheet=34|OwnerPartId=-1|Location.X=728|Location.Y=305|Color=8388608|FontID=1|IsHidden=T|Text=SCES365K|Name=DatasheetVersion
|RECORD=41|OwnerIndex=638|IndexInSheet=35|OwnerPartId=-1|Location.X=728|Location.Y=305|Color=8388608|FontID=1|IsHidden=T|Text=CMOS/TTL|Name=Input Type
|RECORD=41|OwnerIndex=638|IndexInSheet=36|OwnerPartId=-1|Location.X=728|Location.Y=305|Color=8388608|FontID=1|IsHidden=T|Text=Catalog|Name=Rating
|RECORD=41|OwnerIndex=638|IndexInSheet=37|OwnerPartId=-1|Location.X=728|Location.Y=305|Color=8388608|FontID=1|IsHidden=T|Text=32/-32|Name=Output Drive (IOL/IOH)(Max)(mA)
|RECORD=41|OwnerIndex=638|IndexInSheet=38|OwnerPartId=-1|Location.X=728|Location.Y=305|Color=8388608|FontID=1|IsHidden=T|Text=-40 to 125,-40 to 85|Name=Operating Temperature Range(C)
|RECORD=34|OwnerIndex=638|IndexInSheet=-1|OwnerPartId=-1|Location.X=750|Location.Y=290|Color=8388608|FontID=1|Text=U3|Name=Designator|ReadOnlyState=1
|RECORD=41|OwnerIndex=638|IndexInSheet=-1|OwnerPartId=-1|Location.X=749|Location.Y=244|Color=8388608|FontID=1|Text=SN74LVC3G07DCUR|Name=Comment
|RECORD=44|OwnerIndex=638
|RECORD=45|OwnerIndex=688|IndexInSheet=-1|Description=SOP, 8-Leads, Body 2.4x2.1mm, Pitch 0.5mm, IPC Medium Density|UseComponentLibrary=T|ModelName=DCU0008A_N|ModelType=PCBLIB|DatafileCount=1|ModelDatafileEntity0=DCU0008A_N|ModelDatafileKind0=PCBLib|IsCurrent=T|DatalinksLocked=T|DatabaseDatalinksLocked=T
|RECORD=46|OwnerIndex=689
|RECORD=48|OwnerIndex=689
|RECORD=41|OwnerIndex=691|IndexInSheet=-1|OwnerPartId=-1|Color=8388608|FontID=1|IsHidden=T|Text=2D|Name=Available Preview Images
|RECORD=45|OwnerIndex=688|IndexInSheet=-1|Description=SOP, 8-Leads, Body 2.4x2.1mm, Pitch 0.5mm, IPC Low Density|UseComponentLibrary=T|ModelName=DCU0008A_M|ModelType=PCBLIB|DatafileCount=1|ModelDatafileEntity0=DCU0008A_M|ModelDatafileKind0=PCBLib|DatalinksLocked=T|DatabaseDatalinksLocked=T
|RECORD=46|OwnerIndex=693
|RECORD=48|OwnerIndex=693
|RECORD=41|OwnerIndex=695|IndexInSheet=-1|OwnerPartId=-1|Color=8388608|FontID=1|IsHidden=T|Text=2D|Name=Available Preview Images
|RECORD=45|OwnerIndex=688|IndexInSheet=-1|Description=SOP, 8-Leads, Body 2.4x2.1mm, Pitch 0.5mm, IPC High Density|UseComponentLibrary=T|ModelName=DCU0008A_L|ModelType=PCBLIB|DatafileCount=1|ModelDatafileEntity0=DCU0008A_L|ModelDatafileKind0=PCBLib|DatalinksLocked=T|DatabaseDatalinksLocked=T
|RECORD=46|OwnerIndex=697
|RECORD=48|OwnerIndex=697
|RECORD=41|OwnerIndex=699|IndexInSheet=-1|OwnerPartId=-1|Color=8388608|FontID=1|IsHidden=T|Text=2D|Name=Available Preview Images
|RECORD=1|LibReference=b4654b650e69147ec39a6b967a45e02|ComponentDescription=None|PartCount=2|DisplayModeCount=1|IndexInSheet=53|OwnerPartId=-1|Location.X=700|Location.Y=280|CurrentPartId=1|LibraryPath=*|SourceLibraryName=Altium Content Vault|TargetFileName=*|AreaColor=11599871|Color=128|PartIDLocked=T|DesignItemId=CMP-14477-000330-2|AllPinCount=2
|RECORD=2|OwnerIndex=701|OwnerPartId=1|Electrical=4|PinConglomerate=33|PinLength=7|Location.X=700|Location.Y=273|Name=1|Designator=1|PinPropagationDelay=0.000000E+000
|RECORD=2|OwnerIndex=701|OwnerPartId=1|Electrical=4|PinConglomerate=35|PinLength=6|Location.X=700|Location.Y=266|Name=2|Designator=2|PinPropagationDelay=0.000000E+000
|RECORD=13|OwnerIndex=701|IsNotAccesible=T|IndexInSheet=2|OwnerPartId=1|Location.X=710|Location.Y=273|Corner.X=690|Corner.Y=273|LineWidth=1|Color=16711680
|RECORD=13|OwnerIndex=701|IsNotAccesible=T|IndexInSheet=3|OwnerPartId=1|Location.X=710|Location.Y=267|Corner.X=690|Corner.Y=267|LineWidth=1|Color=16711680
|RECORD=13|OwnerIndex=701|IsNotAccesible=T|IndexInSheet=4|OwnerPartId=1|Location.X=700|Location.Y=273|Corner.X=700|Corner.Y=276|LineWidth=1|Color=16711680
|RECORD=13|OwnerIndex=701|IsNotAccesible=T|IndexInSheet=5|OwnerPartId=1|Location.X=700|Location.Y=266|Corner.X=700|Corner.Y=265|LineWidth=1|Color=16711680
|RECORD=41|OwnerIndex=701|IndexInSheet=6|OwnerPartId=-1|Location.X=689|Location.Y=282|Color=8388608|FontID=1|IsHidden=T|Text=Yes|Name=RoHS Compliant
|RECORD=41|OwnerIndex=701|IndexInSheet=7|OwnerPartId=-1|Location.X=689|Location.Y=282|Color=8388608|FontID=1|IsHidden=T|Text=SMD/SMT|Name=Termination
|RECORD=41|OwnerIndex=701|IndexInSheet=8|OwnerPartId=-1|Location.X=689|Location.Y=282|Color=8388608|FontID=1|IsHidden=T|Text=Tape and Reel|Name=Packaging
|RECORD=41|OwnerIndex=701|IndexInSheet=9|OwnerPartId=-1|Location.X=689|Location.Y=282|Color=8388608|FontID=1|IsHidden=T|Text=50V|Name=Voltage Rating (DC)
|RECORD=41|OwnerIndex=701|IndexInSheet=10|OwnerPartId=-1|Location.X=689|Location.Y=282|Color=8388608|FontID=1|IsHidden=T|Text=100nF|Name=Capacitance
|RECORD=41|OwnerIndex=701|IndexInSheet=11|OwnerPartId=-1|Location.X=689|Location.Y=282|Color=8388608|FontID=1|IsHidden=T|Text=0.5mm|Name=Height
|RECORD=41|OwnerIndex=701|IndexInSheet=12|OwnerPartId=-1|Location.X=689|Location.Y=282|Color=8388608|FontID=1|IsHidden=T|Text=Halogen Free|Name=Halogen Free
|RECORD=41|OwnerIndex=701|IndexInSheet=13|OwnerPartId=-1|Location.X=689|Location.Y=282|Color=8388608|FontID=1|IsHidden=T|Text=1005|Name=Case Code (Metric)
|RECORD=41|OwnerIndex=701|IndexInSheet=14|OwnerPartId=-1|Location.X=689|Location.Y=282|Color=8388608|FontID=1|IsHidden=T|Text=0.02inch|Name=Width
|RECORD=41|OwnerIndex=701|IndexInSheet=15|OwnerPartId=-1|Location.X=689|Location.Y=282|Color=8388608|FontID=1|IsHidden=T|Text=85°C|Name=Max Operating Temperature
|RECORD=41|OwnerIndex=701|IndexInSheet=16|OwnerPartId=-1|Location.X=689|Location.Y=282|Color=8388608|FontID=1|IsHidden=T|Text=50V|Name=Voltage Rating
|RECORD=41|OwnerIndex=701|IndexInSheet=17|OwnerPartId=-1|Location.X=689|Location.Y=282|Color=8388608|FontID=1|IsHidden=T|Text=-55°C|Name=Min Operating Temperature
|RECORD=41|OwnerIndex=701|IndexInSheet=18|OwnerPartId=-1|Location.X=689|Location.Y=282|Color=8388608|FontID=1|IsHidden=T|Text=10000|Name=Package Quantity
|RECORD=41|OwnerIndex=701|IndexInSheet=19|OwnerPartId=-1|Location.X=689|Location.Y=282|Color=8388608|FontID=1|IsHidden=T|Text=0402|Name=Case/Package
|RECORD=41|OwnerIndex=701|IndexInSheet=20|OwnerPartId=-1|Location.X=689|Location.Y=282|Color=8388608|FontID=1|IsHidden=T|Text=0402|Name=Case Code (Imperial)
|RECORD=41|OwnerIndex=701|IndexInSheet=21|OwnerPartId=-1|Location.X=689|Location.Y=282|Color=8388608|FontID=1|IsHidden=T|Text=X5R|Name=Dielectric
|RECORD=41|OwnerIndex=701|IndexInSheet=22|OwnerPartId=-1|Location.X=689|Location.Y=282|Color=8388608|FontID=1|IsHidden=T|Text=10%|Name=Tolerance
|RECORD=41|OwnerIndex=701|IndexInSheet=23|OwnerPartId=-1|Location.X=689|Location.Y=282|Color=8388608|FontID=1|IsHidden=T|Text=0.039inch|Name=Length
|RECORD=41|OwnerIndex=701|IndexInSheet=24|OwnerPartId=-1|Location.X=689|Location.Y=282|Color=8388608|FontID=1|IsHidden=T|Text=0.022inch|Name=Thickness
|RECORD=41|OwnerIndex=701|IndexInSheet=25|OwnerPartId=-1|Location.X=689|Location.Y=282|Color=8388608|FontID=1|IsHidden=T|Text=Surface Mount|Name=Mount
|RECORD=34|OwnerIndex=701|IndexInSheet=-1|OwnerPartId=-1|Location.X=711|Location.Y=267|Color=8388608|FontID=1|Text=C9|Name=Designator|ReadOnlyState=1
|RECORD=41|OwnerIndex=701|IndexInSheet=-1|OwnerPartId=1|Location.X=711|Location.Y=257|Color=8388608|FontID=1|Text=100nF|Name=Comment
|RECORD=44|OwnerIndex=701
|RECORD=45|OwnerIndex=732|IndexInSheet=-1|UseComponentLibrary=T|ModelName=FP-0402-L_1_0_0_05-W_0_5-IPC_B|ModelType=PCBLIB|DatafileCount=1|ModelDatafileEntity0=FP-0402-L_1_0_0_05-W_0_5-IPC_B|ModelDatafileKind0=PCBLib|IsCurrent=T|DatalinksLocked=T|DatabaseDatalinksLocked=T
|RECORD=46|OwnerIndex=733
|RECORD=48|OwnerIndex=733
|RECORD=45|OwnerIndex=732|IndexInSheet=-1|UseComponentLibrary=T|ModelName=FP-0402-L_1_0_0_05-W_0_5-IPC_A|ModelType=PCBLIB|DatafileCount=1|ModelDatafileEntity0=FP-0402-L_1_0_0_05-W_0_5-IPC_A|ModelDatafileKind0=PCBLib|DatalinksLocked=T|DatabaseDatalinksLocked=T
|RECORD=46|OwnerIndex=736
|RECORD=48|OwnerIndex=736
|RECORD=45|OwnerIndex=732|IndexInSheet=-1|UseComponentLibrary=T|ModelName=FP-0402-L_1_0_0_05-W_0_5-MFG|ModelType=PCBLIB|DatafileCount=1|ModelDatafileEntity0=FP-0402-L_1_0_0_05-W_0_5-MFG|ModelDatafileKind0=PCBLib|DatalinksLocked=T|DatabaseDatalinksLocked=T
|RECORD=46|OwnerIndex=739
|RECORD=48|OwnerIndex=739
|RECORD=45|OwnerIndex=732|IndexInSheet=-1|UseComponentLibrary=T|ModelName=UMK105BJ104_V-F|ModelType=SIM|IsCurrent=T|DatalinksLocked=T|DatabaseDatalinksLocked=T
|RECORD=46|OwnerIndex=742
|RECORD=48|OwnerIndex=742
|RECORD=41|OwnerIndex=744|IndexInSheet=-1|OwnerPartId=-1|Color=8388608|FontID=1|IsHidden=T|Text=General|Name=Kind
|RECORD=41|OwnerIndex=744|IndexInSheet=-1|OwnerPartId=-1|Color=8388608|FontID=1|IsHidden=T|Text=Spice Subcircuit|Name=SubKind
|RECORD=41|OwnerIndex=744|IndexInSheet=-1|OwnerPartId=-1|Color=8388608|FontID=1|IsHidden=T|Name=Spice Prefix
|RECORD=41|OwnerIndex=744|IndexInSheet=-1|OwnerPartId=-1|Color=8388608|FontID=1|IsHidden=T|Name=Excluded Parts
|RECORD=41|OwnerIndex=744|IndexInSheet=-1|OwnerPartId=-1|Color=8388608|FontID=1|IsHidden=T|Name=Netlist
|RECORD=41|OwnerIndex=744|IndexInSheet=-1|OwnerPartId=-1|Color=8388608|FontID=1|IsHidden=T|Text=document_sim_cache\PIVZSDOR\0|Name=SimulationCacheLocation|ReadOnlyState=3
|RECORD=45|OwnerIndex=732|IndexInSheet=-1|UseComponentLibrary=T|ModelName=FP-0402-L_1_0_0_05-W_0_5-IPC_C|ModelType=PCBLIB|DatafileCount=1|ModelDatafileEntity0=FP-0402-L_1_0_0_05-W_0_5-IPC_C|ModelDatafileKind0=PCBLib|DatalinksLocked=T|DatabaseDatalinksLocked=T
|RECORD=46|OwnerIndex=751
|RECORD=48|OwnerIndex=751
|RECORD=17|IndexInSheet=54|OwnerPartId=-1|Style=4|ShowNetName=F|Location.X=700|Location.Y=260|Orientation=3|Color=128|FontID=1|Text=GND
|RECORD=17|IndexInSheet=55|OwnerPartId=-1|Style=2|ShowNetName=T|Location.X=700|Location.Y=280|Orientation=1|Color=128|FontID=1|Text=VCC
|RECORD=17|IndexInSheet=56|OwnerPartId=-1|Style=4|ShowNetName=F|Location.X=840|Location.Y=280|Orientation=3|Color=128|FontID=1|Text=GND
|RECORD=25|IndexInSheet=57|OwnerPartId=-1|Location.X=680|Location.Y=480|Color=128|FontID=1|Text=ANT_OFF
|RECORD=25|IndexInSheet=58|OwnerPartId=-1|Location.X=870|Location.Y=410|Justification=2|Color=128|FontID=1|Text=ANT_DET
|RECORD=25|IndexInSheet=59|OwnerPartId=-1|Location.X=870|Location.Y=340|Justification=2|Color=128|FontID=1|Text=ANT_SHORT_N
|RECORD=4|IndexInSheet=60|OwnerPartId=-1|Location.X=30|Location.Y=690|Color=8388608|FontID=15|Text=Antenna Supervisor
|RECORD=17|IndexInSheet=61|OwnerPartId=-1|Style=4|ShowNetName=F|Location.X=200|Location.Y=270|Orientation=3|Color=128|FontID=1|Text=GND
|RECORD=25|IndexInSheet=62|OwnerPartId=-1|Location.X=220|Location.Y=360|Color=128|FontID=1|Text=RF_IN
|RECORD=1|LibReference=b4654b650e69147ec39a6b967a45e02|ComponentDescription=None|PartCount=2|DisplayModeCount=1|IndexInSheet=63|OwnerPartId=-1|Location.X=280|Location.Y=350|CurrentPartId=1|LibraryPath=*|SourceLibraryName=Altium Content Vault|TargetFileName=*|AreaColor=11599871|Color=128|PartIDLocked=T|DesignItemId=CMP-14477-000330-2|AllPinCount=2
|RECORD=2|OwnerIndex=763|OwnerPartId=1|Electrical=4|PinConglomerate=33|PinLength=7|Location.X=280|Location.Y=343|Name=1|Designator=1|PinPropagationDelay=0.000000E+000
|RECORD=2|OwnerIndex=763|OwnerPartId=1|Electrical=4|PinConglomerate=35|PinLength=6|Location.X=280|Location.Y=336|Name=2|Designator=2|PinPropagationDelay=0.000000E+000
|RECORD=13|OwnerIndex=763|IsNotAccesible=T|IndexInSheet=2|OwnerPartId=1|Location.X=290|Location.Y=343|Corner.X=270|Corner.Y=343|LineWidth=1|Color=16711680
|RECORD=13|OwnerIndex=763|IsNotAccesible=T|IndexInSheet=3|OwnerPartId=1|Location.X=290|Location.Y=337|Corner.X=270|Corner.Y=337|LineWidth=1|Color=16711680
|RECORD=13|OwnerIndex=763|IsNotAccesible=T|IndexInSheet=4|OwnerPartId=1|Location.X=280|Location.Y=343|Corner.X=280|Corner.Y=346|LineWidth=1|Color=16711680
|RECORD=13|OwnerIndex=763|IsNotAccesible=T|IndexInSheet=5|OwnerPartId=1|Location.X=280|Location.Y=336|Corner.X=280|Corner.Y=335|LineWidth=1|Color=16711680
|RECORD=41|OwnerIndex=763|IndexInSheet=6|OwnerPartId=-1|Location.X=269|Location.Y=352|Color=8388608|FontID=1|IsHidden=T|Text=Yes|Name=RoHS Compliant
|RECORD=41|OwnerIndex=763|IndexInSheet=7|OwnerPartId=-1|Location.X=269|Location.Y=352|Color=8388608|FontID=1|IsHidden=T|Text=SMD/SMT|Name=Termination
|RECORD=41|OwnerIndex=763|IndexInSheet=8|OwnerPartId=-1|Location.X=269|Location.Y=352|Color=8388608|FontID=1|IsHidden=T|Text=Tape and Reel|Name=Packaging
|RECORD=41|OwnerIndex=763|IndexInSheet=9|OwnerPartId=-1|Location.X=269|Location.Y=352|Color=8388608|FontID=1|IsHidden=T|Text=50V|Name=Voltage Rating (DC)
|RECORD=41|OwnerIndex=763|IndexInSheet=10|OwnerPartId=-1|Location.X=269|Location.Y=352|Color=8388608|FontID=1|IsHidden=T|Text=100nF|Name=Capacitance
|RECORD=41|OwnerIndex=763|IndexInSheet=11|OwnerPartId=-1|Location.X=269|Location.Y=352|Color=8388608|FontID=1|IsHidden=T|Text=0.5mm|Name=Height
|RECORD=41|OwnerIndex=763|IndexInSheet=12|OwnerPartId=-1|Location.X=269|Location.Y=352|Color=8388608|FontID=1|IsHidden=T|Text=Halogen Free|Name=Halogen Free
|RECORD=41|OwnerIndex=763|IndexInSheet=13|OwnerPartId=-1|Location.X=269|Location.Y=352|Color=8388608|FontID=1|IsHidden=T|Text=1005|Name=Case Code (Metric)
|RECORD=41|OwnerIndex=763|IndexInSheet=14|OwnerPartId=-1|Location.X=269|Location.Y=352|Color=8388608|FontID=1|IsHidden=T|Text=0.02inch|Name=Width
|RECORD=41|OwnerIndex=763|IndexInSheet=15|OwnerPartId=-1|Location.X=269|Location.Y=352|Color=8388608|FontID=1|IsHidden=T|Text=85°C|Name=Max Operating Temperature
|RECORD=41|OwnerIndex=763|IndexInSheet=16|OwnerPartId=-1|Location.X=269|Location.Y=352|Color=8388608|FontID=1|IsHidden=T|Text=50V|Name=Voltage Rating
|RECORD=41|OwnerIndex=763|IndexInSheet=17|OwnerPartId=-1|Location.X=269|Location.Y=352|Color=8388608|FontID=1|IsHidden=T|Text=-55°C|Name=Min Operating Temperature
|RECORD=41|OwnerIndex=763|IndexInSheet=18|OwnerPartId=-1|Location.X=269|Location.Y=352|Color=8388608|FontID=1|IsHidden=T|Text=10000|Name=Package Quantity
|RECORD=41|OwnerIndex=763|IndexInSheet=19|OwnerPartId=-1|Location.X=269|Location.Y=352|Color=8388608|FontID=1|IsHidden=T|Text=0402|Name=Case/Package
|RECORD=41|OwnerIndex=763|IndexInSheet=20|OwnerPartId=-1|Location.X=269|Location.Y=352|Color=8388608|FontID=1|IsHidden=T|Text=0402|Name=Case Code (Imperial)
|RECORD=41|OwnerIndex=763|IndexInSheet=21|OwnerPartId=-1|Location.X=269|Location.Y=352|Color=8388608|FontID=1|IsHidden=T|Text=X5R|Name=Dielectric
|RECORD=41|OwnerIndex=763|IndexInSheet=22|OwnerPartId=-1|Location.X=269|Location.Y=352|Color=8388608|FontID=1|IsHidden=T|Text=10%|Name=Tolerance
|RECORD=41|OwnerIndex=763|IndexInSheet=23|OwnerPartId=-1|Location.X=269|Location.Y=352|Color=8388608|FontID=1|IsHidden=T|Text=0.039inch|Name=Length
|RECORD=41|OwnerIndex=763|IndexInSheet=24|OwnerPartId=-1|Location.X=269|Location.Y=352|Color=8388608|FontID=1|IsHidden=T|Text=0.022inch|Name=Thickness
|RECORD=41|OwnerIndex=763|IndexInSheet=25|OwnerPartId=-1|Location.X=269|Location.Y=352|Color=8388608|FontID=1|IsHidden=T|Text=Surface Mount|Name=Mount
|RECORD=34|OwnerIndex=763|IndexInSheet=-1|OwnerPartId=-1|Location.X=291|Location.Y=337|Color=8388608|FontID=1|Text=C8|Name=Designator|ReadOnlyState=1
|RECORD=41|OwnerIndex=763|IndexInSheet=-1|OwnerPartId=1|Location.X=291|Location.Y=327|Color=8388608|FontID=1|Text=100nF|Name=Comment
|RECORD=44|OwnerIndex=763
|RECORD=45|OwnerIndex=794|IndexInSheet=-1|UseComponentLibrary=T|ModelName=FP-0402-L_1_0_0_05-W_0_5-IPC_B|ModelType=PCBLIB|DatafileCount=1|ModelDatafileEntity0=FP-0402-L_1_0_0_05-W_0_5-IPC_B|ModelDatafileKind0=PCBLib|IsCurrent=T|DatalinksLocked=T|DatabaseDatalinksLocked=T
|RECORD=46|OwnerIndex=795
|RECORD=48|OwnerIndex=795
|RECORD=45|OwnerIndex=794|IndexInSheet=-1|UseComponentLibrary=T|ModelName=FP-0402-L_1_0_0_05-W_0_5-IPC_A|ModelType=PCBLIB|DatafileCount=1|ModelDatafileEntity0=FP-0402-L_1_0_0_05-W_0_5-IPC_A|ModelDatafileKind0=PCBLib|DatalinksLocked=T|DatabaseDatalinksLocked=T
|RECORD=46|OwnerIndex=798
|RECORD=48|OwnerIndex=798
|RECORD=45|OwnerIndex=794|IndexInSheet=-1|UseComponentLibrary=T|ModelName=FP-0402-L_1_0_0_05-W_0_5-MFG|ModelType=PCBLIB|DatafileCount=1|ModelDatafileEntity0=FP-0402-L_1_0_0_05-W_0_5-MFG|ModelDatafileKind0=PCBLib|DatalinksLocked=T|DatabaseDatalinksLocked=T
|RECORD=46|OwnerIndex=801
|RECORD=48|OwnerIndex=801
|RECORD=45|OwnerIndex=794|IndexInSheet=-1|UseComponentLibrary=T|ModelName=UMK105BJ104_V-F|ModelType=SIM|IsCurrent=T|DatalinksLocked=T|DatabaseDatalinksLocked=T
|RECORD=46|OwnerIndex=804
|RECORD=48|OwnerIndex=804
|RECORD=41|OwnerIndex=806|IndexInSheet=-1|OwnerPartId=-1|Color=8388608|FontID=1|IsHidden=T|Text=General|Name=Kind
|RECORD=41|OwnerIndex=806|IndexInSheet=-1|OwnerPartId=-1|Color=8388608|FontID=1|IsHidden=T|Text=Spice Subcircuit|Name=SubKind
|RECORD=41|OwnerIndex=806|IndexInSheet=-1|OwnerPartId=-1|Color=8388608|FontID=1|IsHidden=T|Name=Spice Prefix
|RECORD=41|OwnerIndex=806|IndexInSheet=-1|OwnerPartId=-1|Color=8388608|FontID=1|IsHidden=T|Name=Excluded Parts
|RECORD=41|OwnerIndex=806|IndexInSheet=-1|OwnerPartId=-1|Color=8388608|FontID=1|IsHidden=T|Name=Netlist
|RECORD=41|OwnerIndex=806|IndexInSheet=-1|OwnerPartId=-1|Color=8388608|FontID=1|IsHidden=T|Text=document_sim_cache\PIVZSDOR\0|Name=SimulationCacheLocation|ReadOnlyState=3
|RECORD=45|OwnerIndex=794|IndexInSheet=-1|UseComponentLibrary=T|ModelName=FP-0402-L_1_0_0_05-W_0_5-IPC_C|ModelType=PCBLIB|DatafileCount=1|ModelDatafileEntity0=FP-0402-L_1_0_0_05-W_0_5-IPC_C|ModelDatafileKind0=PCBLib|DatalinksLocked=T|DatabaseDatalinksLocked=T
|RECORD=46|OwnerIndex=813
|RECORD=48|OwnerIndex=813
|RECORD=28|IndexInSheet=64|OwnerPartId=-1|Location.X=710|Location.Y=190|Corner.X=840|Corner.Y=220|AreaColor=16777215|FontID=1|IsSolid=T|Alignment=1|WordWrap=T|ClipToRect=T|Text=ANT_OFF (active high): pin is low to enable an external antenna.|TextMargin_Frac=5
|RECORD=28|IndexInSheet=65|OwnerPartId=-1|Location.X=450|Location.Y=580|Corner.X=490|Corner.Y=600|AreaColor=16777215|FontID=1|IsSolid=T|Alignment=1|WordWrap=T|ClipToRect=T|Text=High-side Switch~1|TextMargin_Frac=5
|RECORD=1|LibReference=Resistor_300mil|ComponentDescription=RES, 25 OHM, 2%, 1.5W, 150PPM/C, 0603|PartCount=2|DisplayModeCount=1|IndexInSheet=66|OwnerPartId=-1|Location.X=400|Location.Y=360|CurrentPartId=1|LibraryPath=*|SourceLibraryName=RL Research Altium Server|TargetFileName=*|AreaColor=11599871|Color=128|PartIDLocked=T|DesignItemId=RES-CMP-00725-3|AllPinCount=2
|RECORD=2|OwnerIndex=818|OwnerPartId=1|FormalType=1|Electrical=4|PinConglomerate=33|PinLength=9|Location.X=400|Location.Y=351|Name=1|Designator=1|PinPropagationDelay=0.000000E+000
|RECORD=2|OwnerIndex=818|OwnerPartId=1|FormalType=1|Electrical=4|PinConglomerate=35|PinLength=9|Location.X=400|Location.Y=339|Name=2|Designator=2|PinPropagationDelay=0.000000E+000
|RECORD=6|OwnerIndex=818|IsNotAccesible=T|IndexInSheet=2|OwnerPartId=1|LineWidth=1|Color=16711680|LocationCount=8|X1=400|Y1=339|X2=398|Y2=340|X3=402|Y3=342|X4=398|Y4=344|X5=402|Y5=346|X6=398|Y6=348|X7=402|Y7=350|X8=400|Y8=351
|RECORD=41|OwnerIndex=818|IndexInSheet=3|OwnerPartId=-1|Location.X=395|Location.Y=375|Color=8388608|FontID=2|IsHidden=T|Text=https://www.digikey.com/en/products/detail/vishay-dale/RCP0603W25R0GEB/5481868?s=N4IgTCBcDaIEoGEAKAGAbCgzAdTAVjhQHEBRAIRAF0BfIA|Name=Datasheet URL
|RECORD=41|OwnerIndex=818|IndexInSheet=4|OwnerPartId=-1|Location.X=403|Location.Y=332|Color=8388608|FontID=1|Text=25|Name=Resistance
|RECORD=41|OwnerIndex=818|IndexInSheet=5|OwnerPartId=-1|Location.X=403|Location.Y=322|Color=8388608|FontID=1|Text=1.5W|Name=Power (Watts)
|RECORD=41|OwnerIndex=818|IndexInSheet=6|OwnerPartId=-1|Location.X=395|Location.Y=395|Color=8388608|FontID=1|IsHidden=T|Text=±150ppm/°C|Name=Temperature Coefficient
|RECORD=41|OwnerIndex=818|IndexInSheet=7|OwnerPartId=-1|Location.X=395|Location.Y=395|Color=8388608|FontID=1|IsHidden=T|Text=541-2654-1-ND|Name=Supplier Part Number 1
|RECORD=41|OwnerIndex=818|IndexInSheet=8|OwnerPartId=-1|Location.X=403|Location.Y=312|Color=8388608|FontID=1|Text=±2%|Name=Tolerance
|RECORD=41|OwnerIndex=818|IndexInSheet=9|OwnerPartId=-1|Location.X=395|Location.Y=405|Color=8388608|FontID=1|IsHidden=T|Name=Part Status
|RECORD=41|OwnerIndex=818|IndexInSheet=10|OwnerPartId=-1|Location.X=395|Location.Y=405|Color=8388608|FontID=1|IsHidden=T|Text=Moisture Resistant|Name=Features
|RECORD=41|OwnerIndex=818|IndexInSheet=11|OwnerPartId=-1|Location.X=395|Location.Y=405|Color=8388608|FontID=1|IsHidden=T|Text=Chip Resistor - Surface Mount|Name=Category
|RECORD=41|OwnerIndex=818|IndexInSheet=12|OwnerPartId=-1|Location.X=395|Location.Y=405|Color=8388608|FontID=1|IsHidden=T|Text=0.063" L x 0.032" W (1.60mm x 0.81mm)|Name=Size / Dimension
|RECORD=41|OwnerIndex=818|IndexInSheet=13|OwnerPartId=-1|Location.X=395|Location.Y=405|Color=8388608|FontID=1|IsHidden=T|Name=Mounting Type
|RECORD=41|OwnerIndex=818|IndexInSheet=14|OwnerPartId=-1|Location.X=395|Location.Y=405|Color=8388608|FontID=1|IsHidden=T|Text=Digikey|Name=Supplier 1
|RECORD=41|OwnerIndex=818|IndexInSheet=15|OwnerPartId=-1|Location.X=395|Location.Y=405|Color=8388608|FontID=1|IsHidden=T|Text=0.023" (0.58mm)|Name=Height
|RECORD=41|OwnerIndex=818|IndexInSheet=16|OwnerPartId=-1|Location.X=395|Location.Y=405|Color=8388608|FontID=1|IsHidden=T|Name=Termination Style
|RECORD=41|OwnerIndex=818|IndexInSheet=17|OwnerPartId=-1|Location.X=395|Location.Y=405|Color=8388608|FontID=1|IsHidden=T|Text=0603 (1608 Metric)|Name=Case/Package
|RECORD=41|OwnerIndex=818|IndexInSheet=18|OwnerPartId=-1|Location.X=395|Location.Y=405|Color=8388608|FontID=1|IsHidden=T|Name=Ratings
|RECORD=41|OwnerIndex=818|IndexInSheet=19|OwnerPartId=-1|Location.X=395|Location.Y=405|Color=8388608|FontID=1|IsHidden=T|Text=Yes|Name=RoHS
|RECORD=41|OwnerIndex=818|IndexInSheet=20|OwnerPartId=-1|Location.X=395|Location.Y=405|Color=8388608|FontID=1|IsHidden=T|Text=Thick Film|Name=Composition
|RECORD=41|OwnerIndex=818|IndexInSheet=21|OwnerPartId=-1|Location.X=395|Location.Y=405|Color=8388608|FontID=1|IsHidden=T|Text=822-00198-00|Name=Internal Part Number
|RECORD=41|OwnerIndex=818|IndexInSheet=22|OwnerPartId=-1|Location.X=395|Location.Y=405|Color=8388608|FontID=1|IsHidden=T|Text=155°C|Name=Max Operating Temperature
|RECORD=41|OwnerIndex=818|IndexInSheet=23|OwnerPartId=-1|Location.X=395|Location.Y=405|Color=8388608|FontID=1|IsHidden=T|Text=Vishay|Name=Manufacturer
|RECORD=41|OwnerIndex=818|IndexInSheet=24|OwnerPartId=-1|Location.X=395|Location.Y=405|Color=8388608|FontID=1|IsHidden=T|Text=-65°C|Name=Min Operating Temperature
|RECORD=41|OwnerIndex=818|IndexInSheet=25|OwnerPartId=-1|Location.X=395|Location.Y=405|Color=8388608|FontID=1|IsHidden=T|Text=RCP|Name=Series
|RECORD=41|OwnerIndex=818|IndexInSheet=26|OwnerPartId=-1|Location.X=395|Location.Y=405|Color=8388608|FontID=1|IsHidden=T|Text=RCP0603W25R0GEB|Name=Manufacturer Part Number
|RECORD=34|OwnerIndex=818|IndexInSheet=-1|OwnerPartId=-1|Location.X=403|Location.Y=342|Color=8388608|FontID=1|Text=R12|Name=Designator|ReadOnlyState=1
|RECORD=41|OwnerIndex=818|IndexInSheet=-1|OwnerPartId=-1|Location.X=395|Location.Y=345|Color=8388608|FontID=1|IsHidden=T|Text=Vishay_RCP0603W25R0GEB|Name=Comment
|RECORD=44|OwnerIndex=818
|RECORD=45|OwnerIndex=850|IndexInSheet=-1|Description=Chip Resistor, Body 1.6x0.8mm, Height 0.55mm|UseComponentLibrary=T|ModelName=RESC1608X055N|ModelType=PCBLIB|DatafileCount=1|ModelDatafileEntity0=RESC1608X055N|ModelDatafileKind0=PCBLib|IsCurrent=T|DatalinksLocked=T|DatabaseDatalinksLocked=T
|RECORD=46|OwnerIndex=851
|RECORD=48|OwnerIndex=851
|RECORD=41|OwnerIndex=853|IndexInSheet=-1|OwnerPartId=-1|Color=8388608|FontID=1|IsHidden=T|Text=2D|Name=Available Preview Images
|RECORD=14|IndexInSheet=67|OwnerPartId=-1|Location.X=670|Location.Y=230|Corner.X=880|Corner.Y=520|Color=128|AreaColor=11599871
|RECORD=4|IndexInSheet=68|OwnerPartId=-1|Location.X=670|Location.Y=520|Color=8388608|FontID=16|Text=Buffer
|RECORD=14|IndexInSheet=69|OwnerPartId=-1|Location.X=150|Location.Y=250|Corner.X=370|Corner.Y=410|Color=128|AreaColor=11599871
|RECORD=4|IndexInSheet=70|OwnerPartId=-1|Location.X=150|Location.Y=410|Color=8388608|FontID=16|Text=Bias tee
|RECORD=25|IndexInSheet=71|OwnerPartId=-1|Location.X=220|Location.Y=290|Color=128|FontID=1|Text=RF_ANT
|RECORD=43|IndexInSheet=73|OwnerPartId=-1|Location.X=210|Location.Y=350|Color=255|Orientation=2|Name=RF
|RECORD=41|OwnerIndex=860|OwnerPartId=-1|Location.X=139|Location.X_Frac=58995|Location.Y=334|Color=8388608|FontID=1|IsHidden=T|Text=RF|Name=ClassName
|RECORD=1|LibReference=TI-SN74XXX3G0X-XX-8|ComponentDescription=Triple Buffer/Driver With Open-Drain Output, DCU0008A, LARGE T&R|PartCount=5|DisplayModeCount=1|IndexInSheet=74|OwnerPartId=-1|Location.X=750|Location.Y=500|CurrentPartId=3|LibraryPath=*|SourceLibraryName=Altium Content Vault|TargetFileName=*|AreaColor=11599871|Color=128|PartIDLocked=F|DesignItemId=CMP-0859-00615-3|AllPinCount=8
|RECORD=2|OwnerIndex=862|OwnerPartId=3|FormalType=1|Electrical=3|PinConglomerate=48|PinLength=20|Location.X=780|Location.Y=480|Name=3Y|Designator=2|SwapIDPart=Ž&Ž2|PinPropagationDelay=0.000000E+000
|RECORD=2|OwnerIndex=862|OwnerPartId=3|FormalType=1|PinConglomerate=50|PinLength=20|Location.X=750|Location.Y=480|Name=3A|Designator=6|SwapIDPart=Ž&Ž2|PinPropagationDelay=0.000000E+000
|RECORD=13|OwnerIndex=862|IsNotAccesible=T|IndexInSheet=2|OwnerPartId=3|Location.X=750|Location.Y=495|Corner.X=780|Corner.Y=480|LineWidth=1|Color=16711680
|RECORD=13|OwnerIndex=862|IsNotAccesible=T|IndexInSheet=3|OwnerPartId=3|Location.X=750|Location.Y=465|Corner.X=780|Corner.Y=480|LineWidth=1|Color=16711680
|RECORD=13|OwnerIndex=862|IsNotAccesible=T|IndexInSheet=4|OwnerPartId=3|Location.X=750|Location.Y=465|Corner.X=750|Corner.Y=495|LineWidth=1|Color=16711680
|RECORD=2|OwnerIndex=862|OwnerPartId=2|FormalType=1|Electrical=3|PinConglomerate=48|PinLength=20|Location.X=780|Location.Y=480|Name=2Y|Designator=5|SwapIDPart=Ž&Ž2|PinPropagationDelay=0.000000E+000
|RECORD=2|OwnerIndex=862|OwnerPartId=2|FormalType=1|PinConglomerate=50|PinLength=20|Location.X=750|Location.Y=480|Name=2A|Designator=3|SwapIDPart=Ž&Ž2|PinPropagationDelay=0.000000E+000
|RECORD=13|OwnerIndex=862|IsNotAccesible=T|IndexInSheet=7|OwnerPartId=2|Location.X=750|Location.Y=495|Corner.X=780|Corner.Y=480|LineWidth=1|Color=16711680
|RECORD=13|OwnerIndex=862|IsNotAccesible=T|IndexInSheet=8|OwnerPartId=2|Location.X=750|Location.Y=465|Corner.X=780|Corner.Y=480|LineWidth=1|Color=16711680
|RECORD=13|OwnerIndex=862|IsNotAccesible=T|IndexInSheet=9|OwnerPartId=2|Location.X=750|Location.Y=465|Corner.X=750|Corner.Y=495|LineWidth=1|Color=16711680
|RECORD=14|OwnerIndex=862|IsNotAccesible=T|IndexInSheet=10|OwnerPartId=4|Location.X=750|Location.Y=480|Corner.X=810|Corner.Y=500|Color=128|AreaColor=11599871|IsSolid=T
|RECORD=2|OwnerIndex=862|OwnerPartId=4|FormalType=1|Electrical=7|PinConglomerate=56|PinLength=20|Location.X=810|Location.Y=490|Name=GND|Designator=4|PinPropagationDelay=0.000000E+000
|RECORD=2|OwnerIndex=862|OwnerPartId=4|FormalType=1|Electrical=7|PinConglomerate=58|PinLength=20|Location.X=750|Location.Y=490|Name=VCC|Designator=8|PinPropagationDelay=0.000000E+000
|RECORD=2|OwnerIndex=862|OwnerPartId=1|FormalType=1|Electrical=3|PinConglomerate=48|PinLength=20|Location.X=780|Location.Y=480|Name=1Y|Designator=7|SwapIDPart=Ž&Ž2|PinPropagationDelay=0.000000E+000
|RECORD=2|OwnerIndex=862|OwnerPartId=1|FormalType=1|PinConglomerate=50|PinLength=20|Location.X=750|Location.Y=480|Name=1A|Designator=1|SwapIDPart=Ž&Ž2|PinPropagationDelay=0.000000E+000
|RECORD=13|OwnerIndex=862|IsNotAccesible=T|IndexInSheet=15|OwnerPartId=1|Location.X=750|Location.Y=495|Corner.X=780|Corner.Y=480|LineWidth=1|Color=16711680
|RECORD=13|OwnerIndex=862|IsNotAccesible=T|IndexInSheet=16|OwnerPartId=1|Location.X=750|Location.Y=465|Corner.X=780|Corner.Y=480|LineWidth=1|Color=16711680
|RECORD=13|OwnerIndex=862|IsNotAccesible=T|IndexInSheet=17|OwnerPartId=1|Location.X=750|Location.Y=465|Corner.X=750|Corner.Y=495|LineWidth=1|Color=16711680
|RECORD=41|OwnerIndex=862|IndexInSheet=18|OwnerPartId=-1|Location.X=728|Location.Y=515|Color=8388608|FontID=1|IsHidden=T|Text=SN74LVC3G07|Name=Generic Part Number
|RECORD=41|OwnerIndex=862|IndexInSheet=19|OwnerPartId=-1|Location.X=728|Location.Y=515|Color=8388608|FontID=1|IsHidden=T|Text=5.5|Name=VCC(Max)(V)
|RECORD=41|OwnerIndex=862|IndexInSheet=20|OwnerPartId=-1|Location.X=728|Location.Y=515|Color=8388608|FontID=1|IsHidden=T|Text=Non-Inverting Buffer/Driver|Name=Sub-Family
|RECORD=41|OwnerIndex=862|IndexInSheet=21|OwnerPartId=-1|Location.X=728|Location.Y=515|Color=8388608|FontID=1|IsHidden=T|Text=True|Name=Logic
|RECORD=41|OwnerIndex=862|IndexInSheet=22|OwnerPartId=-1|Location.X=728|Location.Y=515|Color=8388608|FontID=1|IsHidden=T|Text=DCU0008A|Name=PackageReference
|RECORD=41|OwnerIndex=862|IndexInSheet=23|OwnerPartId=-1|Location.X=728|Location.Y=515|Color=8388608|FontID=1|IsHidden=T|Text=8.3,4.8,4.2,3.4|Name=tpd @ Nom Voltage(Max)(ns)
|RECORD=41|OwnerIndex=862|IndexInSheet=24|OwnerPartId=-1|Location.X=728|Location.Y=515|Color=8388608|FontID=1|IsHidden=T|Text=CMOS|Name=Output Type
|RECORD=41|OwnerIndex=862|IndexInSheet=25|OwnerPartId=-1|Location.X=728|Location.Y=515|Color=8388608|FontID=1|IsHidden=T|Text=150|Name=F @ Nom Voltage(Max)(Mhz)
|RECORD=41|OwnerIndex=862|IndexInSheet=26|OwnerPartId=-1|Location.X=728|Location.Y=515|Color=8388608|FontID=1|IsHidden=T|Text=LVC|Name=Technology Family
|RECORD=41|OwnerIndex=862|IndexInSheet=27|OwnerPartId=-1|Location.X=728|Location.Y=515|Color=8388608|FontID=1|IsHidden=T|Text=0.01|Name=ICC @ Nom Voltage(Max)(mA)
|RECORD=41|OwnerIndex=862|IndexInSheet=28|OwnerPartId=-1|Location.X=728|Location.Y=515|Color=8388608|FontID=1|IsHidden=T|Text=1.8,2.5,3.3,5|Name=Voltage(Nom)(V)
|RECORD=41|OwnerIndex=862|IndexInSheet=29|OwnerPartId=-1|Location.X=728|Location.Y=515|Color=8388608|FontID=1|IsHidden=T|Text=No|Name=Schmitt Trigger
|RECORD=41|OwnerIndex=862|IndexInSheet=30|OwnerPartId=-1|Location.X=728|Location.Y=515|Color=8388608|FontID=1|IsHidden=T|Text=Texas Instruments|Name=Manufacturer
|RECORD=41|OwnerIndex=862|IndexInSheet=31|OwnerPartId=-1|Location.X=728|Location.Y=515|Color=8388608|FontID=1|IsHidden=T|Text=1.65|Name=VCC(Min)(V)
|RECORD=41|OwnerIndex=862|IndexInSheet=32|OwnerPartId=-1|Location.X=728|Location.Y=515|Color=8388608|FontID=1|IsHidden=T|Text=No|Name=3-State Output
|RECORD=41|OwnerIndex=862|IndexInSheet=33|OwnerPartId=-1|Location.X=728|Location.Y=515|Color=8388608|FontID=1|IsHidden=T|Text=3|Name=Bits(#)
|RECORD=41|OwnerIndex=862|IndexInSheet=34|OwnerPartId=-1|Location.X=728|Location.Y=515|Color=8388608|FontID=1|IsHidden=T|Text=SCES365K|Name=DatasheetVersion
|RECORD=41|OwnerIndex=862|IndexInSheet=35|OwnerPartId=-1|Location.X=728|Location.Y=515|Color=8388608|FontID=1|IsHidden=T|Text=CMOS/TTL|Name=Input Type
|RECORD=41|OwnerIndex=862|IndexInSheet=36|OwnerPartId=-1|Location.X=728|Location.Y=515|Color=8388608|FontID=1|IsHidden=T|Text=Catalog|Name=Rating
|RECORD=41|OwnerIndex=862|IndexInSheet=37|OwnerPartId=-1|Location.X=728|Location.Y=515|Color=8388608|FontID=1|IsHidden=T|Text=32/-32|Name=Output Drive (IOL/IOH)(Max)(mA)
|RECORD=41|OwnerIndex=862|IndexInSheet=38|OwnerPartId=-1|Location.X=728|Location.Y=515|Color=8388608|FontID=1|IsHidden=T|Text=-40 to 125,-40 to 85|Name=Operating Temperature Range(C)
|RECORD=34|OwnerIndex=862|IndexInSheet=-1|OwnerPartId=-1|Location.X=749|Location.Y=496|Color=8388608|FontID=1|Text=U3|Name=Designator|ReadOnlyState=1
|RECORD=41|OwnerIndex=862|IndexInSheet=-1|OwnerPartId=-1|Location.X=749|Location.Y=454|Color=8388608|FontID=1|Text=SN74LVC3G07DCUR|Name=Comment
|RECORD=44|OwnerIndex=862
|RECORD=45|OwnerIndex=912|IndexInSheet=-1|Description=SOP, 8-Leads, Body 2.4x2.1mm, Pitch 0.5mm, IPC Medium Density|UseComponentLibrary=T|ModelName=DCU0008A_N|ModelType=PCBLIB|DatafileCount=1|ModelDatafileEntity0=DCU0008A_N|ModelDatafileKind0=PCBLib|IsCurrent=T|DatalinksLocked=T|DatabaseDatalinksLocked=T
|RECORD=46|OwnerIndex=913
|RECORD=48|OwnerIndex=913
|RECORD=41|OwnerIndex=915|IndexInSheet=-1|OwnerPartId=-1|Color=8388608|FontID=1|IsHidden=T|Text=2D|Name=Available Preview Images
|RECORD=45|OwnerIndex=912|IndexInSheet=-1|Description=SOP, 8-Leads, Body 2.4x2.1mm, Pitch 0.5mm, IPC Low Density|UseComponentLibrary=T|ModelName=DCU0008A_M|ModelType=PCBLIB|DatafileCount=1|ModelDatafileEntity0=DCU0008A_M|ModelDatafileKind0=PCBLib|DatalinksLocked=T|DatabaseDatalinksLocked=T
|RECORD=46|OwnerIndex=917
|RECORD=48|OwnerIndex=917
|RECORD=41|OwnerIndex=919|IndexInSheet=-1|OwnerPartId=-1|Color=8388608|FontID=1|IsHidden=T|Text=2D|Name=Available Preview Images
|RECORD=45|OwnerIndex=912|IndexInSheet=-1|Description=SOP, 8-Leads, Body 2.4x2.1mm, Pitch 0.5mm, IPC High Density|UseComponentLibrary=T|ModelName=DCU0008A_L|ModelType=PCBLIB|DatafileCount=1|ModelDatafileEntity0=DCU0008A_L|ModelDatafileKind0=PCBLib|DatalinksLocked=T|DatabaseDatalinksLocked=T
|RECORD=46|OwnerIndex=921
|RECORD=48|OwnerIndex=921
|RECORD=41|OwnerIndex=923|IndexInSheet=-1|OwnerPartId=-1|Color=8388608|FontID=1|IsHidden=T|Text=2D|Name=Available Preview Images
|RECORD=1|LibReference=TI-SN74XXX3G0X-XX-8|ComponentDescription=Triple Buffer/Driver With Open-Drain Output, DCU0008A, LARGE T&R|PartCount=5|DisplayModeCount=1|IndexInSheet=75|OwnerPartId=-1|Location.X=750|Location.Y=430|CurrentPartId=1|LibraryPath=*|SourceLibraryName=Altium Content Vault|TargetFileName=*|AreaColor=11599871|Color=128|PartIDLocked=T|DesignItemId=CMP-0859-00615-3|AllPinCount=8
|RECORD=2|OwnerIndex=925|OwnerPartId=3|FormalType=1|Electrical=3|PinConglomerate=48|PinLength=20|Location.X=780|Location.Y=410|Name=3Y|Designator=2|SwapIDPart=Ž&Ž2|PinPropagationDelay=0.000000E+000
|RECORD=2|OwnerIndex=925|OwnerPartId=3|FormalType=1|PinConglomerate=50|PinLength=20|Location.X=750|Location.Y=410|Name=3A|Designator=6|SwapIDPart=Ž&Ž2|PinPropagationDelay=0.000000E+000
|RECORD=13|OwnerIndex=925|IsNotAccesible=T|IndexInSheet=2|OwnerPartId=3|Location.X=750|Location.Y=425|Corner.X=780|Corner.Y=410|LineWidth=1|Color=16711680
|RECORD=13|OwnerIndex=925|IsNotAccesible=T|IndexInSheet=3|OwnerPartId=3|Location.X=750|Location.Y=395|Corner.X=780|Corner.Y=410|LineWidth=1|Color=16711680
|RECORD=13|OwnerIndex=925|IsNotAccesible=T|IndexInSheet=4|OwnerPartId=3|Location.X=750|Location.Y=395|Corner.X=750|Corner.Y=425|LineWidth=1|Color=16711680
|RECORD=2|OwnerIndex=925|OwnerPartId=2|FormalType=1|Electrical=3|PinConglomerate=48|PinLength=20|Location.X=780|Location.Y=410|Name=2Y|Designator=5|SwapIDPart=Ž&Ž2|PinPropagationDelay=0.000000E+000
|RECORD=2|OwnerIndex=925|OwnerPartId=2|FormalType=1|PinConglomerate=50|PinLength=20|Location.X=750|Location.Y=410|Name=2A|Designator=3|SwapIDPart=Ž&Ž2|PinPropagationDelay=0.000000E+000
|RECORD=13|OwnerIndex=925|IsNotAccesible=T|IndexInSheet=7|OwnerPartId=2|Location.X=750|Location.Y=425|Corner.X=780|Corner.Y=410|LineWidth=1|Color=16711680
|RECORD=13|OwnerIndex=925|IsNotAccesible=T|IndexInSheet=8|OwnerPartId=2|Location.X=750|Location.Y=395|Corner.X=780|Corner.Y=410|LineWidth=1|Color=16711680
|RECORD=13|OwnerIndex=925|IsNotAccesible=T|IndexInSheet=9|OwnerPartId=2|Location.X=750|Location.Y=395|Corner.X=750|Corner.Y=425|LineWidth=1|Color=16711680
|RECORD=14|OwnerIndex=925|IsNotAccesible=T|IndexInSheet=10|OwnerPartId=4|Location.X=750|Location.Y=410|Corner.X=810|Corner.Y=430|Color=128|AreaColor=11599871|IsSolid=T
|RECORD=2|OwnerIndex=925|OwnerPartId=4|FormalType=1|Electrical=7|PinConglomerate=56|PinLength=20|Location.X=810|Location.Y=420|Name=GND|Designator=4|PinPropagationDelay=0.000000E+000
|RECORD=2|OwnerIndex=925|OwnerPartId=4|FormalType=1|Electrical=7|PinConglomerate=58|PinLength=20|Location.X=750|Location.Y=420|Name=VCC|Designator=8|PinPropagationDelay=0.000000E+000
|RECORD=2|OwnerIndex=925|OwnerPartId=1|FormalType=1|Electrical=3|PinConglomerate=48|PinLength=20|Location.X=780|Location.Y=410|Name=1Y|Designator=7|SwapIDPart=Ž&Ž2|PinPropagationDelay=0.000000E+000
|RECORD=2|OwnerIndex=925|OwnerPartId=1|FormalType=1|PinConglomerate=50|PinLength=20|Location.X=750|Location.Y=410|Name=1A|Designator=1|SwapIDPart=Ž&Ž2|PinPropagationDelay=0.000000E+000
|RECORD=13|OwnerIndex=925|IsNotAccesible=T|IndexInSheet=15|OwnerPartId=1|Location.X=750|Location.Y=425|Corner.X=780|Corner.Y=410|LineWidth=1|Color=16711680
|RECORD=13|OwnerIndex=925|IsNotAccesible=T|IndexInSheet=16|OwnerPartId=1|Location.X=750|Location.Y=395|Corner.X=780|Corner.Y=410|LineWidth=1|Color=16711680
|RECORD=13|OwnerIndex=925|IsNotAccesible=T|IndexInSheet=17|OwnerPartId=1|Location.X=750|Location.Y=395|Corner.X=750|Corner.Y=425|LineWidth=1|Color=16711680
|RECORD=41|OwnerIndex=925|IndexInSheet=18|OwnerPartId=-1|Location.X=728|Location.Y=445|Color=8388608|FontID=1|IsHidden=T|Text=SN74LVC3G07|Name=Generic Part Number
|RECORD=41|OwnerIndex=925|IndexInSheet=19|OwnerPartId=-1|Location.X=728|Location.Y=445|Color=8388608|FontID=1|IsHidden=T|Text=5.5|Name=VCC(Max)(V)
|RECORD=41|OwnerIndex=925|IndexInSheet=20|OwnerPartId=-1|Location.X=728|Location.Y=445|Color=8388608|FontID=1|IsHidden=T|Text=Non-Inverting Buffer/Driver|Name=Sub-Family
|RECORD=41|OwnerIndex=925|IndexInSheet=21|OwnerPartId=-1|Location.X=728|Location.Y=445|Color=8388608|FontID=1|IsHidden=T|Text=True|Name=Logic
|RECORD=41|OwnerIndex=925|IndexInSheet=22|OwnerPartId=-1|Location.X=728|Location.Y=445|Color=8388608|FontID=1|IsHidden=T|Text=DCU0008A|Name=PackageReference
|RECORD=41|OwnerIndex=925|IndexInSheet=23|OwnerPartId=-1|Location.X=728|Location.Y=445|Color=8388608|FontID=1|IsHidden=T|Text=8.3,4.8,4.2,3.4|Name=tpd @ Nom Voltage(Max)(ns)
|RECORD=41|OwnerIndex=925|IndexInSheet=24|OwnerPartId=-1|Location.X=728|Location.Y=445|Color=8388608|FontID=1|IsHidden=T|Text=CMOS|Name=Output Type
|RECORD=41|OwnerIndex=925|IndexInSheet=25|OwnerPartId=-1|Location.X=728|Location.Y=445|Color=8388608|FontID=1|IsHidden=T|Text=150|Name=F @ Nom Voltage(Max)(Mhz)
|RECORD=41|OwnerIndex=925|IndexInSheet=26|OwnerPartId=-1|Location.X=728|Location.Y=445|Color=8388608|FontID=1|IsHidden=T|Text=LVC|Name=Technology Family
|RECORD=41|OwnerIndex=925|IndexInSheet=27|OwnerPartId=-1|Location.X=728|Location.Y=445|Color=8388608|FontID=1|IsHidden=T|Text=0.01|Name=ICC @ Nom Voltage(Max)(mA)
|RECORD=41|OwnerIndex=925|IndexInSheet=28|OwnerPartId=-1|Location.X=728|Location.Y=445|Color=8388608|FontID=1|IsHidden=T|Text=1.8,2.5,3.3,5|Name=Voltage(Nom)(V)
|RECORD=41|OwnerIndex=925|IndexInSheet=29|OwnerPartId=-1|Location.X=728|Location.Y=445|Color=8388608|FontID=1|IsHidden=T|Text=No|Name=Schmitt Trigger
|RECORD=41|OwnerIndex=925|IndexInSheet=30|OwnerPartId=-1|Location.X=728|Location.Y=445|Color=8388608|FontID=1|IsHidden=T|Text=Texas Instruments|Name=Manufacturer
|RECORD=41|OwnerIndex=925|IndexInSheet=31|OwnerPartId=-1|Location.X=728|Location.Y=445|Color=8388608|FontID=1|IsHidden=T|Text=1.65|Name=VCC(Min)(V)
|RECORD=41|OwnerIndex=925|IndexInSheet=32|OwnerPartId=-1|Location.X=728|Location.Y=445|Color=8388608|FontID=1|IsHidden=T|Text=No|Name=3-State Output
|RECORD=41|OwnerIndex=925|IndexInSheet=33|OwnerPartId=-1|Location.X=728|Location.Y=445|Color=8388608|FontID=1|IsHidden=T|Text=3|Name=Bits(#)
|RECORD=41|OwnerIndex=925|IndexInSheet=34|OwnerPartId=-1|Location.X=728|Location.Y=445|Color=8388608|FontID=1|IsHidden=T|Text=SCES365K|Name=DatasheetVersion
|RECORD=41|OwnerIndex=925|IndexInSheet=35|OwnerPartId=-1|Location.X=728|Location.Y=445|Color=8388608|FontID=1|IsHidden=T|Text=CMOS/TTL|Name=Input Type
|RECORD=41|OwnerIndex=925|IndexInSheet=36|OwnerPartId=-1|Location.X=728|Location.Y=445|Color=8388608|FontID=1|IsHidden=T|Text=Catalog|Name=Rating
|RECORD=41|OwnerIndex=925|IndexInSheet=37|OwnerPartId=-1|Location.X=728|Location.Y=445|Color=8388608|FontID=1|IsHidden=T|Text=32/-32|Name=Output Drive (IOL/IOH)(Max)(mA)
|RECORD=41|OwnerIndex=925|IndexInSheet=38|OwnerPartId=-1|Location.X=728|Location.Y=445|Color=8388608|FontID=1|IsHidden=T|Text=-40 to 125,-40 to 85|Name=Operating Temperature Range(C)
|RECORD=34|OwnerIndex=925|IndexInSheet=-1|OwnerPartId=-1|Location.X=749|Location.Y=426|Color=8388608|FontID=1|Text=U3|Name=Designator|ReadOnlyState=1
|RECORD=41|OwnerIndex=925|IndexInSheet=-1|OwnerPartId=-1|Location.X=749|Location.Y=384|Color=8388608|FontID=1|Text=SN74LVC3G07DCUR|Name=Comment
|RECORD=44|OwnerIndex=925
|RECORD=45|OwnerIndex=975|IndexInSheet=-1|Description=SOP, 8-Leads, Body 2.4x2.1mm, Pitch 0.5mm, IPC Medium Density|UseComponentLibrary=T|ModelName=DCU0008A_N|ModelType=PCBLIB|DatafileCount=1|ModelDatafileEntity0=DCU0008A_N|ModelDatafileKind0=PCBLib|IsCurrent=T|DatalinksLocked=T|DatabaseDatalinksLocked=T
|RECORD=46|OwnerIndex=976
|RECORD=48|OwnerIndex=976
|RECORD=41|OwnerIndex=978|IndexInSheet=-1|OwnerPartId=-1|Color=8388608|FontID=1|IsHidden=T|Text=2D|Name=Available Preview Images
|RECORD=45|OwnerIndex=975|IndexInSheet=-1|Description=SOP, 8-Leads, Body 2.4x2.1mm, Pitch 0.5mm, IPC Low Density|UseComponentLibrary=T|ModelName=DCU0008A_M|ModelType=PCBLIB|DatafileCount=1|ModelDatafileEntity0=DCU0008A_M|ModelDatafileKind0=PCBLib|DatalinksLocked=T|DatabaseDatalinksLocked=T
|RECORD=46|OwnerIndex=980
|RECORD=48|OwnerIndex=980
|RECORD=41|OwnerIndex=982|IndexInSheet=-1|OwnerPartId=-1|Color=8388608|FontID=1|IsHidden=T|Text=2D|Name=Available Preview Images
|RECORD=45|OwnerIndex=975|IndexInSheet=-1|Description=SOP, 8-Leads, Body 2.4x2.1mm, Pitch 0.5mm, IPC High Density|UseComponentLibrary=T|ModelName=DCU0008A_L|ModelType=PCBLIB|DatafileCount=1|ModelDatafileEntity0=DCU0008A_L|ModelDatafileKind0=PCBLib|DatalinksLocked=T|DatabaseDatalinksLocked=T
|RECORD=46|OwnerIndex=984
|RECORD=48|OwnerIndex=984
|RECORD=41|OwnerIndex=986|IndexInSheet=-1|OwnerPartId=-1|Color=8388608|FontID=1|IsHidden=T|Text=2D|Name=Available Preview Images
|RECORD=1|LibReference=TI-SN74XXX3G0X-XX-8|ComponentDescription=Triple Buffer/Driver With Open-Drain Output, DCU0008A, LARGE T&R|PartCount=5|DisplayModeCount=1|IndexInSheet=76|OwnerPartId=-1|Location.X=750|Location.Y=360|CurrentPartId=2|LibraryPath=*|SourceLibraryName=Altium Content Vault|TargetFileName=*|AreaColor=11599871|Color=128|PartIDLocked=F|DesignItemId=CMP-0859-00615-3|AllPinCount=8
|RECORD=2|OwnerIndex=988|OwnerPartId=3|FormalType=1|Electrical=3|PinConglomerate=48|PinLength=20|Location.X=780|Location.Y=340|Name=3Y|Designator=2|SwapIDPart=Ž&Ž2|PinPropagationDelay=0.000000E+000
|RECORD=2|OwnerIndex=988|OwnerPartId=3|FormalType=1|PinConglomerate=50|PinLength=20|Location.X=750|Location.Y=340|Name=3A|Designator=6|SwapIDPart=Ž&Ž2|PinPropagationDelay=0.000000E+000
|RECORD=13|OwnerIndex=988|IsNotAccesible=T|IndexInSheet=2|OwnerPartId=3|Location.X=750|Location.Y=355|Corner.X=780|Corner.Y=340|LineWidth=1|Color=16711680
|RECORD=13|OwnerIndex=988|IsNotAccesible=T|IndexInSheet=3|OwnerPartId=3|Location.X=750|Location.Y=325|Corner.X=780|Corner.Y=340|LineWidth=1|Color=16711680
|RECORD=13|OwnerIndex=988|IsNotAccesible=T|IndexInSheet=4|OwnerPartId=3|Location.X=750|Location.Y=325|Corner.X=750|Corner.Y=355|LineWidth=1|Color=16711680
|RECORD=2|OwnerIndex=988|OwnerPartId=2|FormalType=1|Electrical=3|PinConglomerate=48|PinLength=20|Location.X=780|Location.Y=340|Name=2Y|Designator=5|SwapIDPart=Ž&Ž2|PinPropagationDelay=0.000000E+000
|RECORD=2|OwnerIndex=988|OwnerPartId=2|FormalType=1|PinConglomerate=50|PinLength=20|Location.X=750|Location.Y=340|Name=2A|Designator=3|SwapIDPart=Ž&Ž2|PinPropagationDelay=0.000000E+000
|RECORD=13|OwnerIndex=988|IsNotAccesible=T|IndexInSheet=7|OwnerPartId=2|Location.X=750|Location.Y=355|Corner.X=780|Corner.Y=340|LineWidth=1|Color=16711680
|RECORD=13|OwnerIndex=988|IsNotAccesible=T|IndexInSheet=8|OwnerPartId=2|Location.X=750|Location.Y=325|Corner.X=780|Corner.Y=340|LineWidth=1|Color=16711680
|RECORD=13|OwnerIndex=988|IsNotAccesible=T|IndexInSheet=9|OwnerPartId=2|Location.X=750|Location.Y=325|Corner.X=750|Corner.Y=355|LineWidth=1|Color=16711680
|RECORD=14|OwnerIndex=988|IsNotAccesible=T|IndexInSheet=10|OwnerPartId=4|Location.X=750|Location.Y=340|Corner.X=810|Corner.Y=360|Color=128|AreaColor=11599871|IsSolid=T
|RECORD=2|OwnerIndex=988|OwnerPartId=4|FormalType=1|Electrical=7|PinConglomerate=56|PinLength=20|Location.X=810|Location.Y=350|Name=GND|Designator=4|PinPropagationDelay=0.000000E+000
|RECORD=2|OwnerIndex=988|OwnerPartId=4|FormalType=1|Electrical=7|PinConglomerate=58|PinLength=20|Location.X=750|Location.Y=350|Name=VCC|Designator=8|PinPropagationDelay=0.000000E+000
|RECORD=2|OwnerIndex=988|OwnerPartId=1|FormalType=1|Electrical=3|PinConglomerate=48|PinLength=20|Location.X=780|Location.Y=340|Name=1Y|Designator=7|SwapIDPart=Ž&Ž2|PinPropagationDelay=0.000000E+000
|RECORD=2|OwnerIndex=988|OwnerPartId=1|FormalType=1|PinConglomerate=50|PinLength=20|Location.X=750|Location.Y=340|Name=1A|Designator=1|SwapIDPart=Ž&Ž2|PinPropagationDelay=0.000000E+000
|RECORD=13|OwnerIndex=988|IsNotAccesible=T|IndexInSheet=15|OwnerPartId=1|Location.X=750|Location.Y=355|Corner.X=780|Corner.Y=340|LineWidth=1|Color=16711680
|RECORD=13|OwnerIndex=988|IsNotAccesible=T|IndexInSheet=16|OwnerPartId=1|Location.X=750|Location.Y=325|Corner.X=780|Corner.Y=340|LineWidth=1|Color=16711680
|RECORD=13|OwnerIndex=988|IsNotAccesible=T|IndexInSheet=17|OwnerPartId=1|Location.X=750|Location.Y=325|Corner.X=750|Corner.Y=355|LineWidth=1|Color=16711680
|RECORD=41|OwnerIndex=988|IndexInSheet=18|OwnerPartId=-1|Location.X=728|Location.Y=375|Color=8388608|FontID=1|IsHidden=T|Text=SN74LVC3G07|Name=Generic Part Number
|RECORD=41|OwnerIndex=988|IndexInSheet=19|OwnerPartId=-1|Location.X=728|Location.Y=375|Color=8388608|FontID=1|IsHidden=T|Text=5.5|Name=VCC(Max)(V)
|RECORD=41|OwnerIndex=988|IndexInSheet=20|OwnerPartId=-1|Location.X=728|Location.Y=375|Color=8388608|FontID=1|IsHidden=T|Text=Non-Inverting Buffer/Driver|Name=Sub-Family
|RECORD=41|OwnerIndex=988|IndexInSheet=21|OwnerPartId=-1|Location.X=728|Location.Y=375|Color=8388608|FontID=1|IsHidden=T|Text=True|Name=Logic
|RECORD=41|OwnerIndex=988|IndexInSheet=22|OwnerPartId=-1|Location.X=728|Location.Y=375|Color=8388608|FontID=1|IsHidden=T|Text=DCU0008A|Name=PackageReference
|RECORD=41|OwnerIndex=988|IndexInSheet=23|OwnerPartId=-1|Location.X=728|Location.Y=375|Color=8388608|FontID=1|IsHidden=T|Text=8.3,4.8,4.2,3.4|Name=tpd @ Nom Voltage(Max)(ns)
|RECORD=41|OwnerIndex=988|IndexInSheet=24|OwnerPartId=-1|Location.X=728|Location.Y=375|Color=8388608|FontID=1|IsHidden=T|Text=CMOS|Name=Output Type
|RECORD=41|OwnerIndex=988|IndexInSheet=25|OwnerPartId=-1|Location.X=728|Location.Y=375|Color=8388608|FontID=1|IsHidden=T|Text=150|Name=F @ Nom Voltage(Max)(Mhz)
|RECORD=41|OwnerIndex=988|IndexInSheet=26|OwnerPartId=-1|Location.X=728|Location.Y=375|Color=8388608|FontID=1|IsHidden=T|Text=LVC|Name=Technology Family
|RECORD=41|OwnerIndex=988|IndexInSheet=27|OwnerPartId=-1|Location.X=728|Location.Y=375|Color=8388608|FontID=1|IsHidden=T|Text=0.01|Name=ICC @ Nom Voltage(Max)(mA)
|RECORD=41|OwnerIndex=988|IndexInSheet=28|OwnerPartId=-1|Location.X=728|Location.Y=375|Color=8388608|FontID=1|IsHidden=T|Text=1.8,2.5,3.3,5|Name=Voltage(Nom)(V)
|RECORD=41|OwnerIndex=988|IndexInSheet=29|OwnerPartId=-1|Location.X=728|Location.Y=375|Color=8388608|FontID=1|IsHidden=T|Text=No|Name=Schmitt Trigger
|RECORD=41|OwnerIndex=988|IndexInSheet=30|OwnerPartId=-1|Location.X=728|Location.Y=375|Color=8388608|FontID=1|IsHidden=T|Text=Texas Instruments|Name=Manufacturer
|RECORD=41|OwnerIndex=988|IndexInSheet=31|OwnerPartId=-1|Location.X=728|Location.Y=375|Color=8388608|FontID=1|IsHidden=T|Text=1.65|Name=VCC(Min)(V)
|RECORD=41|OwnerIndex=988|IndexInSheet=32|OwnerPartId=-1|Location.X=728|Location.Y=375|Color=8388608|FontID=1|IsHidden=T|Text=No|Name=3-State Output
|RECORD=41|OwnerIndex=988|IndexInSheet=33|OwnerPartId=-1|Location.X=728|Location.Y=375|Color=8388608|FontID=1|IsHidden=T|Text=3|Name=Bits(#)
|RECORD=41|OwnerIndex=988|IndexInSheet=34|OwnerPartId=-1|Location.X=728|Location.Y=375|Color=8388608|FontID=1|IsHidden=T|Text=SCES365K|Name=DatasheetVersion
|RECORD=41|OwnerIndex=988|IndexInSheet=35|OwnerPartId=-1|Location.X=728|Location.Y=375|Color=8388608|FontID=1|IsHidden=T|Text=CMOS/TTL|Name=Input Type
|RECORD=41|OwnerIndex=988|IndexInSheet=36|OwnerPartId=-1|Location.X=728|Location.Y=375|Color=8388608|FontID=1|IsHidden=T|Text=Catalog|Name=Rating
|RECORD=41|OwnerIndex=988|IndexInSheet=37|OwnerPartId=-1|Location.X=728|Location.Y=375|Color=8388608|FontID=1|IsHidden=T|Text=32/-32|Name=Output Drive (IOL/IOH)(Max)(mA)
|RECORD=41|OwnerIndex=988|IndexInSheet=38|OwnerPartId=-1|Location.X=728|Location.Y=375|Color=8388608|FontID=1|IsHidden=T|Text=-40 to 125,-40 to 85|Name=Operating Temperature Range(C)
|RECORD=34|OwnerIndex=988|IndexInSheet=-1|OwnerPartId=-1|Location.X=749|Location.Y=356|Color=8388608|FontID=1|Text=U3|Name=Designator|ReadOnlyState=1
|RECORD=41|OwnerIndex=988|IndexInSheet=-1|OwnerPartId=-1|Location.X=749|Location.Y=314|Color=8388608|FontID=1|Text=SN74LVC3G07DCUR|Name=Comment
|RECORD=44|OwnerIndex=988
|RECORD=45|OwnerIndex=1038|IndexInSheet=-1|Description=SOP, 8-Leads, Body 2.4x2.1mm, Pitch 0.5mm, IPC Medium Density|UseComponentLibrary=T|ModelName=DCU0008A_N|ModelType=PCBLIB|DatafileCount=1|ModelDatafileEntity0=DCU0008A_N|ModelDatafileKind0=PCBLib|IsCurrent=T|DatalinksLocked=T|DatabaseDatalinksLocked=T
|RECORD=46|OwnerIndex=1039
|RECORD=48|OwnerIndex=1039
|RECORD=41|OwnerIndex=1041|IndexInSheet=-1|OwnerPartId=-1|Color=8388608|FontID=1|IsHidden=T|Text=2D|Name=Available Preview Images
|RECORD=45|OwnerIndex=1038|IndexInSheet=-1|Description=SOP, 8-Leads, Body 2.4x2.1mm, Pitch 0.5mm, IPC Low Density|UseComponentLibrary=T|ModelName=DCU0008A_M|ModelType=PCBLIB|DatafileCount=1|ModelDatafileEntity0=DCU0008A_M|ModelDatafileKind0=PCBLib|DatalinksLocked=T|DatabaseDatalinksLocked=T
|RECORD=46|OwnerIndex=1043
|RECORD=48|OwnerIndex=1043
|RECORD=41|OwnerIndex=1045|IndexInSheet=-1|OwnerPartId=-1|Color=8388608|FontID=1|IsHidden=T|Text=2D|Name=Available Preview Images
|RECORD=45|OwnerIndex=1038|IndexInSheet=-1|Description=SOP, 8-Leads, Body 2.4x2.1mm, Pitch 0.5mm, IPC High Density|UseComponentLibrary=T|ModelName=DCU0008A_L|ModelType=PCBLIB|DatafileCount=1|ModelDatafileEntity0=DCU0008A_L|ModelDatafileKind0=PCBLib|DatalinksLocked=T|DatabaseDatalinksLocked=T
|RECORD=46|OwnerIndex=1047
|RECORD=48|OwnerIndex=1047
|RECORD=41|OwnerIndex=1049|IndexInSheet=-1|OwnerPartId=-1|Color=8388608|FontID=1|IsHidden=T|Text=2D|Name=Available Preview Images
|RECORD=1|LibReference=CONN_131-3711-301|ComponentDescription=Rf Coaxial Board Mount Connector|PartCount=2|DisplayModeCount=1|IndexInSheet=77|OwnerPartId=-1|Location.X=160|Location.Y=300|CurrentPartId=1|LibraryPath=*|SourceLibraryName=MyLibrary.IntLib|TargetFileName=*|AreaColor=11599871|Color=128|PartIDLocked=T|DesignItemId=CONN_131-3711-301|AllPinCount=3
|RECORD=41|OwnerIndex=1051|OwnerPartId=-1|Location.X=155|Location.Y=315|Color=8388608|FontID=1|IsHidden=T|Text=Digi-Key|Name=Supplier 1|ReadOnlyState=3
|RECORD=41|OwnerIndex=1051|IndexInSheet=1|OwnerPartId=-1|Location.X=155|Location.Y=325|Color=8388608|FontID=1|IsHidden=T|Text=Bel Cinch|Name=Manufacturer
|RECORD=41|OwnerIndex=1051|IndexInSheet=2|OwnerPartId=-1|Location.X=155|Location.Y=325|Color=8388608|FontID=1|IsHidden=T|Text=131-3711-301|Name=Manufacturer Part Number
|RECORD=41|OwnerIndex=1051|IndexInSheet=3|OwnerPartId=-1|Location.X=155|Location.Y=325|Color=8388608|FontID=1|IsHidden=T|Text=Yes|Name=RoHS
|RECORD=41|OwnerIndex=1051|IndexInSheet=4|OwnerPartId=-1|Location.X=155|Location.Y=325|Color=8388608|FontID=1|IsHidden=T|Text=RF / Coaxial Connectors|Name=Category
|RECORD=41|OwnerIndex=1051|IndexInSheet=5|OwnerPartId=-1|Location.X=155|Location.Y=325|Color=8388608|FontID=1|IsHidden=T|Text=475|Name=Stock 1|ReadOnlyState=3
|RECORD=41|OwnerIndex=1051|IndexInSheet=6|OwnerPartId=-1|Location.X=155|Location.Y=325|Color=8388608|FontID=1|IsHidden=T|Text=1=7.75000, 10=7.00900, 25=6.62160, 50=6.46000, 100=6.13700, 250=5.49100, 500=5.16800, 1000=4.52200 (USD)|Name=Pricing 1|ReadOnlyState=3
|RECORD=41|OwnerIndex=1051|IndexInSheet=7|OwnerPartId=-1|Location.X=155|Location.Y=325|Color=8388608|FontID=1|IsHidden=T|Text=Surface Mount|Name=Mount
|RECORD=41|OwnerIndex=1051|IndexInSheet=8|OwnerPartId=-1|Location.X=155|Location.Y=325|Color=8388608|FontID=1|IsHidden=T|Text=SMA|Name=Case/Package
|RECORD=41|OwnerIndex=1051|IndexInSheet=9|OwnerPartId=-1|Location.X=155|Location.Y=325|Color=8388608|FontID=1|IsHidden=T|Text=Brass|Name=Contact Material
|RECORD=41|OwnerIndex=1051|IndexInSheet=10|OwnerPartId=-1|Location.X=155|Location.Y=325|Color=8388608|FontID=1|IsHidden=T|Text=Gold,Nickel|Name=Contact Plating
|RECORD=41|OwnerIndex=1051|IndexInSheet=11|OwnerPartId=-1|Location.X=155|Location.Y=325|Color=8388608|FontID=1|IsHidden=T|Text=Brass|Name=Body Material
|RECORD=41|OwnerIndex=1051|IndexInSheet=12|OwnerPartId=-1|Location.X=155|Location.Y=325|Color=8388608|FontID=1|IsHidden=T|Text=Nickel|Name=Plating
|RECORD=41|OwnerIndex=1051|IndexInSheet=13|OwnerPartId=-1|Location.X=155|Location.Y=325|Color=8388608|FontID=1|IsHidden=T|Text=Gold|Name=Housing Color
|RECORD=41|OwnerIndex=1051|IndexInSheet=14|OwnerPartId=-1|Location.X=155|Location.Y=325|Color=8388608|FontID=1|IsHidden=T|Text=Gold|Name=Body Plating
|RECORD=41|OwnerIndex=1051|IndexInSheet=15|OwnerPartId=-1|Location.X=155|Location.Y=325|Color=8388608|FontID=1|IsHidden=T|Text=PTFE|Name=Dielectric Material
|RECORD=41|OwnerIndex=1051|IndexInSheet=16|OwnerPartId=-1|Location.X=155|Location.Y=325|Color=8388608|FontID=1|IsHidden=T|Text=Nickel|Name=Shell Plating
|RECORD=41|OwnerIndex=1051|IndexInSheet=17|OwnerPartId=-1|Location.X=155|Location.Y=325|Color=8388608|FontID=1|IsHidden=T|Text=Gold|Name=Center Contact Plating
|RECORD=41|OwnerIndex=1051|IndexInSheet=18|OwnerPartId=-1|Location.X=155|Location.Y=325|Color=8388608|FontID=1|IsHidden=T|Text=-65°C|Name=Min Operating Temperature
|RECORD=41|OwnerIndex=1051|IndexInSheet=19|OwnerPartId=-1|Location.X=155|Location.Y=325|Color=8388608|FontID=1|IsHidden=T|Text=165°C|Name=Max Operating Temperature
|RECORD=41|OwnerIndex=1051|IndexInSheet=20|OwnerPartId=-1|Location.X=155|Location.Y=325|Color=8388608|FontID=1|IsHidden=T|Text=25|Name=Package Quantity
|RECORD=41|OwnerIndex=1051|IndexInSheet=21|OwnerPartId=-1|Location.X=155|Location.Y=325|Color=8388608|FontID=1|IsHidden=T|Text=Bulk|Name=Packaging
|RECORD=41|OwnerIndex=1051|IndexInSheet=22|OwnerPartId=-1|Location.X=155|Location.Y=325|Color=8388608|FontID=1|IsHidden=T|Text=50R|Name=Impedance
|RECORD=41|OwnerIndex=1051|IndexInSheet=23|OwnerPartId=-1|Location.X=155|Location.Y=325|Color=8388608|FontID=1|IsHidden=T|Text=SNAP-ON|Name=Fastening Type
|RECORD=41|OwnerIndex=1051|IndexInSheet=24|OwnerPartId=-1|Location.X=155|Location.Y=325|Color=8388608|FontID=1|IsHidden=T|Text=335V|Name=Voltage Rating
|RECORD=41|OwnerIndex=1051|IndexInSheet=25|OwnerPartId=-1|Location.X=155|Location.Y=325|Color=8388608|FontID=1|IsHidden=T|Text=Female|Name=Gender
|RECORD=41|OwnerIndex=1051|IndexInSheet=26|OwnerPartId=-1|Location.X=155|Location.Y=325|Color=8388608|FontID=1|IsHidden=T|Text=4Hz|Name=Frequency
|RECORD=41|OwnerIndex=1051|IndexInSheet=27|OwnerPartId=-1|Location.X=155|Location.Y=325|Color=8388608|FontID=1|IsHidden=T|Text=SMB,Male Pin|Name=Connector Type
|RECORD=41|OwnerIndex=1051|IndexInSheet=28|OwnerPartId=-1|Location.X=155|Location.Y=325|Color=8388608|FontID=1|IsHidden=T|Text=Solder|Name=Termination
|RECORD=41|OwnerIndex=1051|IndexInSheet=29|OwnerPartId=-1|Location.X=155|Location.Y=325|Color=8388608|FontID=1|IsHidden=T|Text=4GHz|Name=Max Frequency
|RECORD=41|OwnerIndex=1051|IndexInSheet=30|OwnerPartId=-1|Location.X=155|Location.Y=325|Color=8388608|FontID=1|IsHidden=T|Text=Reverse|Name=Polarity
|RECORD=41|OwnerIndex=1051|IndexInSheet=31|OwnerPartId=-1|Location.X=155|Location.Y=325|Color=8388608|FontID=1|IsHidden=T|Text=Right Angle|Name=Orientation
|RECORD=41|OwnerIndex=1051|IndexInSheet=32|OwnerPartId=-1|Location.X=155|Location.Y=325|Color=8388608|FontID=1|IsHidden=T|Text=0 to 4 Hz to GHz|Name=Operating Frequency
|RECORD=41|OwnerIndex=1051|IndexInSheet=33|OwnerPartId=-1|Location.X=155|Location.Y=325|Color=8388608|FontID=2|IsHidden=T|Text=http://www.mouser.com/Search/include/RoHSCompliant.aspx?qs=sxnx5FoGSWlI%252bs7K%252boh9Yg%3d%3d&src-supplier=Mouser|Name=ComponentLink1URL
|RECORD=41|OwnerIndex=1051|IndexInSheet=34|OwnerPartId=-1|Location.X=155|Location.Y=325|Color=8388608|FontID=2|IsHidden=T|Text=http://www.mouser.com/Search/include/RoHSCompliant.aspx?qs=sxnx5FoGSWlI%252bs7K%252boh9Yg%3d%3d&src-supplier=Mouser|Name=ComponentLink1Description
|RECORD=41|OwnerIndex=1051|IndexInSheet=35|OwnerPartId=-1|Location.X=155|Location.Y=325|Color=8388608|FontID=2|IsHidden=T|Text=http://www.mouser.com/Search/include/RoHSCompliant.aspx?qs=BzWiDxlKIe%2fRhe5ZDRBb2Q%3d%3d&src-supplier=Mouser|Name=ComponentLink2URL
|RECORD=41|OwnerIndex=1051|IndexInSheet=36|OwnerPartId=-1|Location.X=155|Location.Y=325|Color=8388608|FontID=2|IsHidden=T|Text=http://www.mouser.com/Search/include/RoHSCompliant.aspx?qs=BzWiDxlKIe%2fRhe5ZDRBb2Q%3d%3d&src-supplier=Mouser|Name=ComponentLink2Description
|RECORD=41|OwnerIndex=1051|IndexInSheet=37|OwnerPartId=-1|Location.X=155|Location.Y=325|Color=8388608|FontID=2|IsHidden=T|Text=http://www.onlinecomponents.com/datasheet/1313711301.aspx?p=11276490&src-supplier=Onlinecomponents.com|Name=ComponentLink3URL
|RECORD=41|OwnerIndex=1051|IndexInSheet=38|OwnerPartId=-1|Location.X=155|Location.Y=325|Color=8388608|FontID=2|IsHidden=T|Text=http://www.onlinecomponents.com/datasheet/1313711301.aspx?p=11276490&src-supplier=Onlinecomponents.com|Name=ComponentLink3Description
|RECORD=41|OwnerIndex=1051|IndexInSheet=39|OwnerPartId=-1|Location.X=155|Location.Y=325|Color=8388608|FontID=2|IsHidden=T|Text=http://www.mouser.com/Search/include/RoHSCompliant.aspx?qs=sxnx5FoGSWlgU0HI%252bkNgTA%3d%3d&src-supplier=Mouser|Name=ComponentLink4URL
|RECORD=41|OwnerIndex=1051|IndexInSheet=40|OwnerPartId=-1|Location.X=155|Location.Y=325|Color=8388608|FontID=2|IsHidden=T|Text=http://www.mouser.com/Search/include/RoHSCompliant.aspx?qs=sxnx5FoGSWlgU0HI%252bkNgTA%3d%3d&src-supplier=Mouser|Name=ComponentLink4Description
|RECORD=41|OwnerIndex=1051|IndexInSheet=41|OwnerPartId=-1|Location.X=155|Location.Y=325|Color=8388608|FontID=2|IsHidden=T|Text=http://www.mouser.com/Search/include/RoHSCompliant.aspx?qs=p2XSgoD%252b2ikka7OcbAcBow%3d%3d&src-supplier=Mouser|Name=ComponentLink5URL
|RECORD=41|OwnerIndex=1051|IndexInSheet=42|OwnerPartId=-1|Location.X=155|Location.Y=325|Color=8388608|FontID=2|IsHidden=T|Text=http://www.mouser.com/Search/include/RoHSCompliant.aspx?qs=p2XSgoD%252b2ikka7OcbAcBow%3d%3d&src-supplier=Mouser|Name=ComponentLink5Description
|RECORD=41|OwnerIndex=1051|IndexInSheet=43|OwnerPartId=-1|Location.X=155|Location.Y=325|Color=8388608|FontID=2|IsHidden=T|Text=http://www.mouser.com/Search/include/RoHSCompliant.aspx?qs=CoHYZihNMM5AOHZHjTCMkA%3d%3d&src-supplier=Mouser|Name=ComponentLink6URL
|RECORD=41|OwnerIndex=1051|IndexInSheet=44|OwnerPartId=-1|Location.X=155|Location.Y=325|Color=8388608|FontID=2|IsHidden=T|Text=http://www.mouser.com/Search/include/RoHSCompliant.aspx?qs=CoHYZihNMM5AOHZHjTCMkA%3d%3d&src-supplier=Mouser|Name=ComponentLink6Description
|RECORD=41|OwnerIndex=1051|IndexInSheet=45|OwnerPartId=-1|Location.X=155|Location.Y=325|Color=8388608|FontID=2|IsHidden=T|Text=http://www.mouser.com/Search/include/RoHSCompliant.aspx?qs=hJAXt0VUbWsyDbF0CdNvSg%3d%3d&src-supplier=Mouser|Name=ComponentLink7URL
|RECORD=41|OwnerIndex=1051|IndexInSheet=46|OwnerPartId=-1|Location.X=155|Location.Y=325|Color=8388608|FontID=2|IsHidden=T|Text=http://www.mouser.com/Search/include/RoHSCompliant.aspx?qs=hJAXt0VUbWsyDbF0CdNvSg%3d%3d&src-supplier=Mouser|Name=ComponentLink7Description
|RECORD=41|OwnerIndex=1051|IndexInSheet=47|OwnerPartId=-1|Location.X=155|Location.Y=315|Color=8388608|FontID=1|IsHidden=T|Text=J10507-ND|Name=Supplier Part Number 1|ReadOnlyState=3
|RECORD=14|OwnerIndex=1051|IsNotAccesible=T|IndexInSheet=48|OwnerPartId=1|Location.X=160|Location.Y=260|Corner.X=180|Corner.Y=300|Color=128|AreaColor=11599871|IsSolid=T
|RECORD=2|OwnerIndex=1051|OwnerPartId=1|FormalType=1|Electrical=4|PinConglomerate=40|PinLength=20|Location.X=180|Location.Y=290|Name=1|Designator=1|SwapIDPart=Ž&Ž||PinPropagationDelay=0.000000E+000
|RECORD=2|OwnerIndex=1051|OwnerPartId=1|FormalType=1|Electrical=4|PinConglomerate=40|PinLength=20|Location.X=180|Location.Y=280|Name=2|Designator=2|SwapIDPart=Ž&Ž||PinPropagationDelay=0.000000E+000
|RECORD=2|OwnerIndex=1051|OwnerPartId=1|FormalType=1|Electrical=4|PinConglomerate=40|PinLength=20|Location.X=180|Location.Y=270|Name=3|Designator=3|SwapIDPart=Ž&Ž||PinPropagationDelay=0.000000E+000
|RECORD=34|OwnerIndex=1051|IndexInSheet=-1|OwnerPartId=-1|Location.X=160|Location.Y=300|Color=8388608|FontID=1|Text=J2|Name=Designator|ReadOnlyState=1
|RECORD=41|OwnerIndex=1051|IndexInSheet=-1|OwnerPartId=-1|Location.X=160|Location.Y=250|Color=8388608|FontID=1|Text=SMB_131-3711-301|Name=Comment
|RECORD=44|OwnerIndex=1051
|RECORD=45|OwnerIndex=1109|IndexInSheet=-1|UseComponentLibrary=T|ModelName=CONN_131-3711-301|ModelType=PCBLIB|DatafileCount=1|ModelDatafileEntity0=CONN_131-3711-301|ModelDatafileKind0=PCBLib|IsCurrent=T|DatalinksLocked=T|DatabaseDatalinksLocked=T|IntegratedModel=T|DatabaseModel=T
|RECORD=46|OwnerIndex=1110
|RECORD=48|OwnerIndex=1110
|RECORD=1|LibReference=1029c3af85768c4190bb7ad29bc67b5|ComponentDescription=1kO ±1% 0.063W 0402 Thick Film Chip Resistor AEC-Q200 compliant|PartCount=2|DisplayModeCount=1|IndexInSheet=78|OwnerPartId=-1|Location.X=390|Location.Y=40|Orientation=1|CurrentPartId=1|LibraryPath=*|SourceLibraryName=Altium Content Vault|TargetFileName=*|AreaColor=11599871|Color=128|PartIDLocked=T|DesignItemId=CMP-26527-000026-1|AllPinCount=2
|RECORD=2|OwnerIndex=1113|OwnerPartId=1|Electrical=4|PinConglomerate=35|PinLength=20|Location.X=390|Location.Y=60|Name=1|Designator=1|PinPropagationDelay=0.000000E+000
|RECORD=2|OwnerIndex=1113|OwnerPartId=1|Electrical=4|PinConglomerate=33|PinLength=20|Location.X=390|Location.Y=90|Name=2|Designator=2|PinPropagationDelay=0.000000E+000
|RECORD=13|OwnerIndex=1113|IsNotAccesible=T|IndexInSheet=2|OwnerPartId=1|Location.X=390|Location.Y=60|Corner.X=385|Corner.Y=63|LineWidth=1|Color=16711680
|RECORD=13|OwnerIndex=1113|IsNotAccesible=T|IndexInSheet=3|OwnerPartId=1|Location.X=385|Location.Y=63|Corner.X=395|Corner.Y=68|LineWidth=1|Color=16711680
|RECORD=13|OwnerIndex=1113|IsNotAccesible=T|IndexInSheet=4|OwnerPartId=1|Location.X=395|Location.Y=68|Corner.X=385|Corner.Y=73|LineWidth=1|Color=16711680
|RECORD=13|OwnerIndex=1113|IsNotAccesible=T|IndexInSheet=5|OwnerPartId=1|Location.X=385|Location.Y=73|Corner.X=395|Corner.Y=78|LineWidth=1|Color=16711680
|RECORD=13|OwnerIndex=1113|IsNotAccesible=T|IndexInSheet=6|OwnerPartId=1|Location.X=395|Location.Y=78|Corner.X=385|Corner.Y=83|LineWidth=1|Color=16711680
|RECORD=13|OwnerIndex=1113|IsNotAccesible=T|IndexInSheet=7|OwnerPartId=1|Location.X=385|Location.Y=83|Corner.X=395|Corner.Y=88|LineWidth=1|Color=16711680
|RECORD=13|OwnerIndex=1113|IsNotAccesible=T|IndexInSheet=8|OwnerPartId=1|Location.X=395|Location.Y=88|Corner.X=390|Corner.Y=90|LineWidth=1|Color=16711680
|RECORD=13|OwnerIndex=1113|IsNotAccesible=T|IndexInSheet=9|OwnerPartId=1|Location.X=390|Location.Y=60|Corner.X=390|Corner.Y=57|LineWidth=1|Color=16711680
|RECORD=13|OwnerIndex=1113|IsNotAccesible=T|IndexInSheet=10|OwnerPartId=1|Location.X=390|Location.Y=90|Corner.X=390|Corner.Y=93|LineWidth=1|Color=16711680
|RECORD=41|OwnerIndex=1113|IndexInSheet=11|OwnerPartId=-1|Location.X=384|Location.Y=112|Color=8388608|FontID=1|IsHidden=T|Text=1mm|Name=Length
|RECORD=41|OwnerIndex=1113|IndexInSheet=12|OwnerPartId=-1|Location.X=384|Location.Y=112|Color=8388608|FontID=1|IsHidden=T|Text=Yes|Name=RoHS Compliant
|RECORD=41|OwnerIndex=1113|IndexInSheet=13|OwnerPartId=-1|Location.X=384|Location.Y=112|Color=8388608|FontID=1|IsHidden=T|Text=Rectangular|Name=Construction
|RECORD=41|OwnerIndex=1113|IndexInSheet=14|OwnerPartId=-1|Location.X=384|Location.Y=112|Color=8388608|FontID=1|IsHidden=T|Text=0.016inch|Name=Height
|RECORD=41|OwnerIndex=1113|IndexInSheet=15|OwnerPartId=-1|Location.X=384|Location.Y=112|Color=8388608|FontID=1|IsHidden=T|Text=0402|Name=Size Code
|RECORD=41|OwnerIndex=1113|IndexInSheet=16|OwnerPartId=-1|Location.X=384|Location.Y=112|Color=8388608|FontID=1|IsHidden=T|Text=Lead Free|Name=Lead Free
|RECORD=41|OwnerIndex=1113|IndexInSheet=17|OwnerPartId=-1|Location.X=384|Location.Y=112|Color=8388608|FontID=1|IsHidden=T|Text=No|Name=Radiation Hardening
|RECORD=41|OwnerIndex=1113|IndexInSheet=18|OwnerPartId=-1|Location.X=384|Location.Y=112|Color=8388608|FontID=1|IsHidden=T|Text=1%|Name=Tolerance
|RECORD=41|OwnerIndex=1113|IndexInSheet=19|OwnerPartId=-1|Location.X=384|Location.Y=112|Color=8388608|FontID=1|IsHidden=T|Text=0.02inch|Name=Width
|RECORD=41|OwnerIndex=1113|IndexInSheet=20|OwnerPartId=-1|Location.X=384|Location.Y=112|Color=8388608|FontID=1|IsHidden=T|Text=1kR|Name=Resistance
|RECORD=41|OwnerIndex=1113|IndexInSheet=21|OwnerPartId=-1|Location.X=384|Location.Y=112|Color=8388608|FontID=1|IsHidden=T|Text=Not|Name=Military Standard
|RECORD=41|OwnerIndex=1113|IndexInSheet=22|OwnerPartId=-1|Location.X=384|Location.Y=112|Color=8388608|FontID=1|IsHidden=T|Text=Thick Film|Name=Resistor Type
|RECORD=41|OwnerIndex=1113|IndexInSheet=23|OwnerPartId=-1|Location.X=384|Location.Y=112|Color=8388608|FontID=1|IsHidden=T|Text=100ppm/°C|Name=Temperature Coefficient
|RECORD=41|OwnerIndex=1113|IndexInSheet=24|OwnerPartId=-1|Location.X=384|Location.Y=112|Color=8388608|FontID=1|IsHidden=T|Text=2|Name=Number of Terminations
|RECORD=41|OwnerIndex=1113|IndexInSheet=25|OwnerPartId=-1|Location.X=384|Location.Y=112|Color=8388608|FontID=1|IsHidden=T|Text=-55°C|Name=Min Operating Temperature
|RECORD=41|OwnerIndex=1113|IndexInSheet=26|OwnerPartId=-1|Location.X=384|Location.Y=112|Color=8388608|FontID=1|IsHidden=T|Text=155°C|Name=Max Operating Temperature
|RECORD=41|OwnerIndex=1113|IndexInSheet=27|OwnerPartId=-1|Location.X=384|Location.Y=112|Color=8388608|FontID=1|IsHidden=T|Text=63mW|Name=Power Rating
|RECORD=41|OwnerIndex=1113|IndexInSheet=28|OwnerPartId=-1|Location.X=384|Location.Y=112|Color=8388608|FontID=1|IsHidden=T|Text=0.5mm|Name=Depth
|RECORD=41|OwnerIndex=1113|IndexInSheet=29|OwnerPartId=-1|Location.X=384|Location.Y=112|Color=8388608|FontID=1|IsHidden=T|Text=Automotive AEC-Q200|Name=Features
|RECORD=41|OwnerIndex=1113|IndexInSheet=30|OwnerPartId=-1|Location.X=384|Location.Y=112|Color=8388608|FontID=1|IsHidden=T|Text=Tape and Reel|Name=Packaging
|RECORD=41|OwnerIndex=1113|IndexInSheet=31|OwnerPartId=-1|Location.X=384|Location.Y=112|Color=8388608|FontID=1|IsHidden=T|Text=1005|Name=Case Code (Metric)
|RECORD=41|OwnerIndex=1113|IndexInSheet=32|OwnerPartId=-1|Location.X=384|Location.Y=112|Color=8388608|FontID=1|IsHidden=T|Text=Surface Mount|Name=Mount
|RECORD=41|OwnerIndex=1113|IndexInSheet=33|OwnerPartId=-1|Location.X=384|Location.Y=112|Color=8388608|FontID=1|IsHidden=T|Text=Tin|Name=Contact Plating
|RECORD=41|OwnerIndex=1113|IndexInSheet=34|OwnerPartId=-1|Location.X=384|Location.Y=112|Color=8388608|FontID=1|IsHidden=T|Text=63mW|Name=Max Power Dissipation
|RECORD=41|OwnerIndex=1113|IndexInSheet=35|OwnerPartId=-1|Location.X=384|Location.Y=112|Color=8388608|FontID=1|IsHidden=T|Text=0402|Name=Case/Package
|RECORD=41|OwnerIndex=1113|IndexInSheet=36|OwnerPartId=-1|Location.X=384|Location.Y=112|Color=8388608|FontID=1|IsHidden=T|Text=0402|Name=Case Code (Imperial)
|RECORD=41|OwnerIndex=1113|IndexInSheet=37|OwnerPartId=-1|Location.X=384|Location.Y=112|Color=8388608|FontID=1|IsHidden=T|Text=RMCF|Name=Series
|RECORD=34|OwnerIndex=1113|IndexInSheet=-1|OwnerPartId=-1|Location.X=396|Location.Y=84|Color=8388608|FontID=1|Text=R13|Name=Designator|ReadOnlyState=1
|RECORD=41|OwnerIndex=1113|IndexInSheet=-1|OwnerPartId=1|Location.X=396|Location.Y=74|Color=8388608|FontID=1|Text=1k|Name=Comment
|RECORD=44|OwnerIndex=1113
|RECORD=45|OwnerIndex=1156|IndexInSheet=-1|UseComponentLibrary=T|ModelName=FP-RMCF0402-MFG|ModelType=PCBLIB|DatafileCount=1|ModelDatafileEntity0=FP-RMCF0402-MFG|ModelDatafileKind0=PCBLib|IsCurrent=T|DatalinksLocked=T|DatabaseDatalinksLocked=T
|RECORD=46|OwnerIndex=1157
|RECORD=48|OwnerIndex=1157
|RECORD=45|OwnerIndex=1156|IndexInSheet=-1|UseComponentLibrary=T|ModelName=FP-RMCF0402-IPC_C|ModelType=PCBLIB|DatafileCount=1|ModelDatafileEntity0=FP-RMCF0402-IPC_C|ModelDatafileKind0=PCBLib|DatalinksLocked=T|DatabaseDatalinksLocked=T
|RECORD=46|OwnerIndex=1160
|RECORD=48|OwnerIndex=1160
|RECORD=45|OwnerIndex=1156|IndexInSheet=-1|UseComponentLibrary=T|ModelName=FP-RMCF0402-IPC_B|ModelType=PCBLIB|DatafileCount=1|ModelDatafileEntity0=FP-RMCF0402-IPC_B|ModelDatafileKind0=PCBLib|DatalinksLocked=T|DatabaseDatalinksLocked=T
|RECORD=46|OwnerIndex=1163
|RECORD=48|OwnerIndex=1163
|RECORD=45|OwnerIndex=1156|IndexInSheet=-1|UseComponentLibrary=T|ModelName=FP-RMCF0402-IPC_A|ModelType=PCBLIB|DatafileCount=1|ModelDatafileEntity0=FP-RMCF0402-IPC_A|ModelDatafileKind0=PCBLib|DatalinksLocked=T|DatabaseDatalinksLocked=T
|RECORD=46|OwnerIndex=1166
|RECORD=48|OwnerIndex=1166
|RECORD=1|LibReference=1029c3af85768c4190bb7ad29bc67b5|ComponentDescription=1kO ±1% 0.063W 0402 Thick Film Chip Resistor AEC-Q200 compliant|PartCount=2|DisplayModeCount=1|IndexInSheet=79|OwnerPartId=-1|Location.X=460|Location.Y=40|Orientation=1|CurrentPartId=1|LibraryPath=*|SourceLibraryName=Altium Content Vault|TargetFileName=*|AreaColor=11599871|Color=128|PartIDLocked=T|DesignItemId=CMP-26527-000026-1|AllPinCount=2
|RECORD=2|OwnerIndex=1169|OwnerPartId=1|Electrical=4|PinConglomerate=35|PinLength=20|Location.X=460|Location.Y=60|Name=1|Designator=1|PinPropagationDelay=0.000000E+000
|RECORD=2|OwnerIndex=1169|OwnerPartId=1|Electrical=4|PinConglomerate=33|PinLength=20|Location.X=460|Location.Y=90|Name=2|Designator=2|PinPropagationDelay=0.000000E+000
|RECORD=13|OwnerIndex=1169|IsNotAccesible=T|IndexInSheet=2|OwnerPartId=1|Location.X=460|Location.Y=60|Corner.X=455|Corner.Y=63|LineWidth=1|Color=16711680
|RECORD=13|OwnerIndex=1169|IsNotAccesible=T|IndexInSheet=3|OwnerPartId=1|Location.X=455|Location.Y=63|Corner.X=465|Corner.Y=68|LineWidth=1|Color=16711680
|RECORD=13|OwnerIndex=1169|IsNotAccesible=T|IndexInSheet=4|OwnerPartId=1|Location.X=465|Location.Y=68|Corner.X=455|Corner.Y=73|LineWidth=1|Color=16711680
|RECORD=13|OwnerIndex=1169|IsNotAccesible=T|IndexInSheet=5|OwnerPartId=1|Location.X=455|Location.Y=73|Corner.X=465|Corner.Y=78|LineWidth=1|Color=16711680
|RECORD=13|OwnerIndex=1169|IsNotAccesible=T|IndexInSheet=6|OwnerPartId=1|Location.X=465|Location.Y=78|Corner.X=455|Corner.Y=83|LineWidth=1|Color=16711680
|RECORD=13|OwnerIndex=1169|IsNotAccesible=T|IndexInSheet=7|OwnerPartId=1|Location.X=455|Location.Y=83|Corner.X=465|Corner.Y=88|LineWidth=1|Color=16711680
|RECORD=13|OwnerIndex=1169|IsNotAccesible=T|IndexInSheet=8|OwnerPartId=1|Location.X=465|Location.Y=88|Corner.X=460|Corner.Y=90|LineWidth=1|Color=16711680
|RECORD=13|OwnerIndex=1169|IsNotAccesible=T|IndexInSheet=9|OwnerPartId=1|Location.X=460|Location.Y=60|Corner.X=460|Corner.Y=57|LineWidth=1|Color=16711680
|RECORD=13|OwnerIndex=1169|IsNotAccesible=T|IndexInSheet=10|OwnerPartId=1|Location.X=460|Location.Y=90|Corner.X=460|Corner.Y=93|LineWidth=1|Color=16711680
|RECORD=41|OwnerIndex=1169|IndexInSheet=11|OwnerPartId=-1|Location.X=454|Location.Y=112|Color=8388608|FontID=1|IsHidden=T|Text=1mm|Name=Length
|RECORD=41|OwnerIndex=1169|IndexInSheet=12|OwnerPartId=-1|Location.X=454|Location.Y=112|Color=8388608|FontID=1|IsHidden=T|Text=Yes|Name=RoHS Compliant
|RECORD=41|OwnerIndex=1169|IndexInSheet=13|OwnerPartId=-1|Location.X=454|Location.Y=112|Color=8388608|FontID=1|IsHidden=T|Text=Rectangular|Name=Construction
|RECORD=41|OwnerIndex=1169|IndexInSheet=14|OwnerPartId=-1|Location.X=454|Location.Y=112|Color=8388608|FontID=1|IsHidden=T|Text=0.016inch|Name=Height
|RECORD=41|OwnerIndex=1169|IndexInSheet=15|OwnerPartId=-1|Location.X=454|Location.Y=112|Color=8388608|FontID=1|IsHidden=T|Text=0402|Name=Size Code
|RECORD=41|OwnerIndex=1169|IndexInSheet=16|OwnerPartId=-1|Location.X=454|Location.Y=112|Color=8388608|FontID=1|IsHidden=T|Text=Lead Free|Name=Lead Free
|RECORD=41|OwnerIndex=1169|IndexInSheet=17|OwnerPartId=-1|Location.X=454|Location.Y=112|Color=8388608|FontID=1|IsHidden=T|Text=No|Name=Radiation Hardening
|RECORD=41|OwnerIndex=1169|IndexInSheet=18|OwnerPartId=-1|Location.X=454|Location.Y=112|Color=8388608|FontID=1|IsHidden=T|Text=1%|Name=Tolerance
|RECORD=41|OwnerIndex=1169|IndexInSheet=19|OwnerPartId=-1|Location.X=454|Location.Y=112|Color=8388608|FontID=1|IsHidden=T|Text=0.02inch|Name=Width
|RECORD=41|OwnerIndex=1169|IndexInSheet=20|OwnerPartId=-1|Location.X=454|Location.Y=112|Color=8388608|FontID=1|IsHidden=T|Text=1kR|Name=Resistance
|RECORD=41|OwnerIndex=1169|IndexInSheet=21|OwnerPartId=-1|Location.X=454|Location.Y=112|Color=8388608|FontID=1|IsHidden=T|Text=Not|Name=Military Standard
|RECORD=41|OwnerIndex=1169|IndexInSheet=22|OwnerPartId=-1|Location.X=454|Location.Y=112|Color=8388608|FontID=1|IsHidden=T|Text=Thick Film|Name=Resistor Type
|RECORD=41|OwnerIndex=1169|IndexInSheet=23|OwnerPartId=-1|Location.X=454|Location.Y=112|Color=8388608|FontID=1|IsHidden=T|Text=100ppm/°C|Name=Temperature Coefficient
|RECORD=41|OwnerIndex=1169|IndexInSheet=24|OwnerPartId=-1|Location.X=454|Location.Y=112|Color=8388608|FontID=1|IsHidden=T|Text=2|Name=Number of Terminations
|RECORD=41|OwnerIndex=1169|IndexInSheet=25|OwnerPartId=-1|Location.X=454|Location.Y=112|Color=8388608|FontID=1|IsHidden=T|Text=-55°C|Name=Min Operating Temperature
|RECORD=41|OwnerIndex=1169|IndexInSheet=26|OwnerPartId=-1|Location.X=454|Location.Y=112|Color=8388608|FontID=1|IsHidden=T|Text=155°C|Name=Max Operating Temperature
|RECORD=41|OwnerIndex=1169|IndexInSheet=27|OwnerPartId=-1|Location.X=454|Location.Y=112|Color=8388608|FontID=1|IsHidden=T|Text=63mW|Name=Power Rating
|RECORD=41|OwnerIndex=1169|IndexInSheet=28|OwnerPartId=-1|Location.X=454|Location.Y=112|Color=8388608|FontID=1|IsHidden=T|Text=0.5mm|Name=Depth
|RECORD=41|OwnerIndex=1169|IndexInSheet=29|OwnerPartId=-1|Location.X=454|Location.Y=112|Color=8388608|FontID=1|IsHidden=T|Text=Automotive AEC-Q200|Name=Features
|RECORD=41|OwnerIndex=1169|IndexInSheet=30|OwnerPartId=-1|Location.X=454|Location.Y=112|Color=8388608|FontID=1|IsHidden=T|Text=Tape and Reel|Name=Packaging
|RECORD=41|OwnerIndex=1169|IndexInSheet=31|OwnerPartId=-1|Location.X=454|Location.Y=112|Color=8388608|FontID=1|IsHidden=T|Text=1005|Name=Case Code (Metric)
|RECORD=41|OwnerIndex=1169|IndexInSheet=32|OwnerPartId=-1|Location.X=454|Location.Y=112|Color=8388608|FontID=1|IsHidden=T|Text=Surface Mount|Name=Mount
|RECORD=41|OwnerIndex=1169|IndexInSheet=33|OwnerPartId=-1|Location.X=454|Location.Y=112|Color=8388608|FontID=1|IsHidden=T|Text=Tin|Name=Contact Plating
|RECORD=41|OwnerIndex=1169|IndexInSheet=34|OwnerPartId=-1|Location.X=454|Location.Y=112|Color=8388608|FontID=1|IsHidden=T|Text=63mW|Name=Max Power Dissipation
|RECORD=41|OwnerIndex=1169|IndexInSheet=35|OwnerPartId=-1|Location.X=454|Location.Y=112|Color=8388608|FontID=1|IsHidden=T|Text=0402|Name=Case/Package
|RECORD=41|OwnerIndex=1169|IndexInSheet=36|OwnerPartId=-1|Location.X=454|Location.Y=112|Color=8388608|FontID=1|IsHidden=T|Text=0402|Name=Case Code (Imperial)
|RECORD=41|OwnerIndex=1169|IndexInSheet=37|OwnerPartId=-1|Location.X=454|Location.Y=112|Color=8388608|FontID=1|IsHidden=T|Text=RMCF|Name=Series
|RECORD=34|OwnerIndex=1169|IndexInSheet=-1|OwnerPartId=-1|Location.X=466|Location.Y=84|Color=8388608|FontID=1|Text=R14|Name=Designator|ReadOnlyState=1
|RECORD=41|OwnerIndex=1169|IndexInSheet=-1|OwnerPartId=1|Location.X=466|Location.Y=74|Color=8388608|FontID=1|Text=1k|Name=Comment
|RECORD=44|OwnerIndex=1169
|RECORD=45|OwnerIndex=1212|IndexInSheet=-1|UseComponentLibrary=T|ModelName=FP-RMCF0402-MFG|ModelType=PCBLIB|DatafileCount=1|ModelDatafileEntity0=FP-RMCF0402-MFG|ModelDatafileKind0=PCBLib|IsCurrent=T|DatalinksLocked=T|DatabaseDatalinksLocked=T
|RECORD=46|OwnerIndex=1213
|RECORD=48|OwnerIndex=1213
|RECORD=45|OwnerIndex=1212|IndexInSheet=-1|UseComponentLibrary=T|ModelName=FP-RMCF0402-IPC_C|ModelType=PCBLIB|DatafileCount=1|ModelDatafileEntity0=FP-RMCF0402-IPC_C|ModelDatafileKind0=PCBLib|DatalinksLocked=T|DatabaseDatalinksLocked=T
|RECORD=46|OwnerIndex=1216
|RECORD=48|OwnerIndex=1216
|RECORD=45|OwnerIndex=1212|IndexInSheet=-1|UseComponentLibrary=T|ModelName=FP-RMCF0402-IPC_B|ModelType=PCBLIB|DatafileCount=1|ModelDatafileEntity0=FP-RMCF0402-IPC_B|ModelDatafileKind0=PCBLib|DatalinksLocked=T|DatabaseDatalinksLocked=T
|RECORD=46|OwnerIndex=1219
|RECORD=48|OwnerIndex=1219
|RECORD=45|OwnerIndex=1212|IndexInSheet=-1|UseComponentLibrary=T|ModelName=FP-RMCF0402-IPC_A|ModelType=PCBLIB|DatafileCount=1|ModelDatafileEntity0=FP-RMCF0402-IPC_A|ModelDatafileKind0=PCBLib|DatalinksLocked=T|DatabaseDatalinksLocked=T
|RECORD=46|OwnerIndex=1222
|RECORD=48|OwnerIndex=1222
|RECORD=25|IndexInSheet=80|OwnerPartId=-1|Location.X=440|Location.Y=40|Justification=2|Color=128|FontID=1|Text=ANT_DET
|RECORD=25|IndexInSheet=81|OwnerPartId=-1|Location.X=540|Location.Y=40|Justification=2|Color=128|FontID=1|Text=ANT_SHORT_N
|RECORD=17|IndexInSheet=82|OwnerPartId=-1|Style=2|ShowNetName=T|Location.X=390|Location.Y=110|Orientation=1|Color=128|FontID=1|Text=VCC
|RECORD=17|IndexInSheet=83|OwnerPartId=-1|Style=2|ShowNetName=T|Location.X=460|Location.Y=110|Orientation=1|Color=128|FontID=1|Text=VCC
|RECORD=14|IndexInSheet=84|OwnerPartId=-1|Location.X=360|Location.Y=30|Corner.X=570|Corner.Y=140|Color=128|AreaColor=11599871
|RECORD=4|IndexInSheet=85|OwnerPartId=-1|Location.X=360|Location.Y=140|Color=8388608|FontID=16|Text=Buffer Pullups
|RECORD=1|LibReference=AMP-OPA-LM7121-5|ComponentDescription=micropower Rail-to-Rail Input and Output Operational Amplifier, 5-pin SC-70, Pb-Free|PartCount=2|DisplayModeCount=1|IndexInSheet=86|OwnerPartId=-1|Location.X=520|Location.Y=430|CurrentPartId=1|LibraryPath=*|SourceLibraryName=Altium Content Vault|TargetFileName=*|AreaColor=11599871|Color=128|PartIDLocked=F|DesignItemId=CMP-0055-01065-3|AllPinCount=5
|RECORD=2|OwnerIndex=1231|OwnerPartId=1|FormalType=1|Electrical=7|PinConglomerate=51|PinLength=20|Location.X=540|Location.Y=390|Name=V-|Designator=2|PinPropagationDelay=0.000000E+000
|RECORD=2|OwnerIndex=1231|OwnerPartId=1|FormalType=1|PinConglomerate=50|PinLength=20|Location.X=520|Location.Y=400|Name=IN+|Designator=3|PinPropagationDelay=0.000000E+000
|RECORD=2|OwnerIndex=1231|OwnerPartId=1|FormalType=1|PinConglomerate=50|PinLength=20|Location.X=520|Location.Y=420|Name=IN-|Designator=4|PinPropagationDelay=0.000000E+000
|RECORD=2|OwnerIndex=1231|OwnerPartId=1|FormalType=1|Electrical=7|PinConglomerate=49|PinLength=20|Location.X=540|Location.Y=430|Name=V+|Designator=5|PinPropagationDelay=0.000000E+000
|RECORD=2|OwnerIndex=1231|OwnerPartId=1|FormalType=1|Electrical=2|PinConglomerate=48|PinLength=20|Location.X=560|Location.Y=410|Name=OUT|Designator=1|PinPropagationDelay=0.000000E+000
|RECORD=13|OwnerIndex=1231|IsNotAccesible=T|IndexInSheet=5|OwnerPartId=1|Location.X=520|Location.Y=430|Corner.X=560|Corner.Y=410|LineWidth=1|Color=16711680
|RECORD=13|OwnerIndex=1231|IsNotAccesible=T|IndexInSheet=6|OwnerPartId=1|Location.X=520|Location.Y=390|Corner.X=560|Corner.Y=410|LineWidth=1|Color=16711680
|RECORD=13|OwnerIndex=1231|IsNotAccesible=T|IndexInSheet=7|OwnerPartId=1|Location.X=520|Location.Y=430|Corner.X=520|Corner.Y=390|LineWidth=1|Color=16711680
|RECORD=13|OwnerIndex=1231|IsNotAccesible=T|IndexInSheet=8|OwnerPartId=1|Location.X=524|Location.Y=420|Corner.X=530|Corner.Y=420|LineWidth=1|Color=16711680
|RECORD=13|OwnerIndex=1231|IsNotAccesible=T|IndexInSheet=9|OwnerPartId=1|Location.X=524|Location.Y=400|Corner.X=530|Corner.Y=400|LineWidth=1|Color=16711680
|RECORD=13|OwnerIndex=1231|IsNotAccesible=T|IndexInSheet=10|OwnerPartId=1|Location.X=527|Location.Y=403|Corner.X=527|Corner.Y=397|LineWidth=1|Color=16711680
|RECORD=13|OwnerIndex=1231|IsNotAccesible=T|IndexInSheet=11|OwnerPartId=1|Location.X=540|Location.Y=430|Corner.X=540|Corner.Y=420|LineWidth=1|Color=16711680
|RECORD=13|OwnerIndex=1231|IsNotAccesible=T|IndexInSheet=12|OwnerPartId=1|Location.X=540|Location.Y=400|Corner.X=540|Corner.Y=390|LineWidth=1|Color=16711680
|RECORD=41|OwnerIndex=1231|IndexInSheet=13|OwnerPartId=-1|Location.X=498|Location.Y=452|Color=8388608|FontID=2|IsHidden=T|Text=http://www.ti.com/general/docs/lit/getliterature.tsp?genericPartNumber=LPV511&fileType=pdf|Name=ComponentLink1URL
|RECORD=41|OwnerIndex=1231|IndexInSheet=14|OwnerPartId=-1|Location.X=498|Location.Y=452|Color=8388608|FontID=1|IsHidden=T|Text=MO-203-AA|Name=Code_JEDEC
|RECORD=41|OwnerIndex=1231|IndexInSheet=15|OwnerPartId=-1|Location.X=498|Location.Y=452|Color=8388608|FontID=1|IsHidden=T|Text=Y|Name=RoHS
|RECORD=41|OwnerIndex=1231|IndexInSheet=16|OwnerPartId=-1|Location.X=498|Location.Y=452|Color=8388608|FontID=1|IsHidden=T|Text=SOT353-5|Name=Code_IPC
|RECORD=41|OwnerIndex=1231|IndexInSheet=17|OwnerPartId=-1|Location.X=498|Location.Y=452|Color=8388608|FontID=1|IsHidden=T|Text=5|Name=PinCount
|RECORD=41|OwnerIndex=1231|IndexInSheet=18|OwnerPartId=-1|Location.X=498|Location.Y=452|Color=8388608|FontID=1|IsHidden=T|Text=Molded SC-70, 2 x 1.25 x .9mm, 5 Lead, 0.65mm Pitch|Name=PackageDescription
|RECORD=41|OwnerIndex=1231|IndexInSheet=19|OwnerPartId=-1|Location.X=498|Location.Y=452|Color=8388608|FontID=1|IsHidden=T|Name=High-Reliability
|RECORD=41|OwnerIndex=1231|IndexInSheet=20|OwnerPartId=-1|Location.X=498|Location.Y=452|Color=8388608|FontID=1|IsHidden=T|Text=Amplifiers|Name=CompType
|RECORD=41|OwnerIndex=1231|IndexInSheet=21|OwnerPartId=-1|Location.X=498|Location.Y=452|Color=8388608|FontID=1|IsHidden=T|Text=Datasheet URL|Name=ComponentLink1Description
|RECORD=41|OwnerIndex=1231|IndexInSheet=22|OwnerPartId=-1|Location.X=498|Location.Y=452|Color=8388608|FontID=1|IsHidden=T|Text=DCK0005A|Name=Package Reference
|RECORD=41|OwnerIndex=1231|IndexInSheet=23|OwnerPartId=-1|Location.X=498|Location.Y=452|Color=8388608|FontID=1|IsHidden=T|Name=PartNumber
|RECORD=41|OwnerIndex=1231|IndexInSheet=24|OwnerPartId=-1|Location.X=498|Location.Y=452|Color=8388608|FontID=1|IsHidden=T|Text=Texas Instruments|Name=Manufacturer
|RECORD=41|OwnerIndex=1231|IndexInSheet=25|OwnerPartId=-1|Location.X=498|Location.Y=452|Color=8388608|FontID=1|IsHidden=T|Text=A91*XTT|Name=PackageTopMarking
|RECORD=41|OwnerIndex=1231|IndexInSheet=26|OwnerPartId=-1|Location.X=498|Location.Y=452|Color=8388608|FontID=1|IsHidden=T|Text=Y|Name=PowerWise
|RECORD=41|OwnerIndex=1231|IndexInSheet=27|OwnerPartId=-1|Location.X=498|Location.Y=452|Color=8388608|FontID=1|IsHidden=T|Text=SC-88A|Name=Code_JEITA
|RECORD=34|OwnerIndex=1231|IndexInSheet=-1|OwnerPartId=-1|Location.X=582|Location.Y=431|Color=8388608|FontID=1|Text=U4|Name=Designator|ReadOnlyState=1
|RECORD=41|OwnerIndex=1231|IndexInSheet=-1|OwnerPartId=-1|Location.X=582|Location.Y=421|Color=8388608|FontID=1|Text=LPV511MGX/NOPB|Name=Comment
|RECORD=44|OwnerIndex=1231
|RECORD=45|OwnerIndex=1267|IndexInSheet=-1|Description=SOT23, 5-Leads, Body 2.15x1.4mm, Pitch 0.65mm, IPC Medium Density|UseComponentLibrary=T|ModelName=DCK0005A_N|ModelType=PCBLIB|DatafileCount=1|ModelDatafileEntity0=DCK0005A_N|ModelDatafileKind0=PCBLib|IsCurrent=T|DatalinksLocked=T|DatabaseDatalinksLocked=T
|RECORD=46|OwnerIndex=1268
|RECORD=48|OwnerIndex=1268
|RECORD=41|OwnerIndex=1270|IndexInSheet=-1|OwnerPartId=-1|Color=8388608|FontID=1|IsHidden=T|Text=2D|Name=Available Preview Images
|RECORD=45|OwnerIndex=1267|IndexInSheet=-1|Description=SOT23, 5-Leads, Body 2.15x1.4mm, Pitch 0.65mm, IPC High Density|UseComponentLibrary=T|ModelName=DCK0005A_L|ModelType=PCBLIB|DatafileCount=1|ModelDatafileEntity0=DCK0005A_L|ModelDatafileKind0=PCBLib|DatalinksLocked=T|DatabaseDatalinksLocked=T
|RECORD=46|OwnerIndex=1272
|RECORD=48|OwnerIndex=1272
|RECORD=41|OwnerIndex=1274|IndexInSheet=-1|OwnerPartId=-1|Color=8388608|FontID=1|IsHidden=T|Text=2D|Name=Available Preview Images
|RECORD=45|OwnerIndex=1267|IndexInSheet=-1|Description=SOT23, 5-Leads, Body 2.15x1.4mm, Pitch 0.65mm, IPC Low Density|UseComponentLibrary=T|ModelName=DCK0005A_M|ModelType=PCBLIB|DatafileCount=1|ModelDatafileEntity0=DCK0005A_M|ModelDatafileKind0=PCBLib|DatalinksLocked=T|DatabaseDatalinksLocked=T
|RECORD=46|OwnerIndex=1276
|RECORD=48|OwnerIndex=1276
|RECORD=41|OwnerIndex=1278|IndexInSheet=-1|OwnerPartId=-1|Color=8388608|FontID=1|IsHidden=T|Text=2D|Name=Available Preview Images
|RECORD=27|IndexInSheet=87|OwnerPartId=-1|LineWidth=1|Color=8388608|LocationCount=2|X1=560|Y1=480|X2=540|Y2=480
|RECORD=27|IndexInSheet=88|OwnerPartId=-1|LineWidth=1|Color=8388608|LocationCount=2|X1=540|Y1=450|X2=540|Y2=480
|RECORD=27|IndexInSheet=89|OwnerPartId=-1|LineWidth=1|Color=8388608|LocationCount=2|X1=400|Y1=290|X2=400|Y2=270
|RECORD=27|IndexInSheet=90|OwnerPartId=-1|LineWidth=1|Color=8388608|LocationCount=2|X1=400|Y1=290|X2=350|Y2=290
|RECORD=27|IndexInSheet=91|OwnerPartId=-1|LineWidth=1|Color=8388608|LocationCount=2|X1=460|Y1=500|X2=460|Y2=550
|RECORD=27|IndexInSheet=92|OwnerPartId=-1|LineWidth=1|Color=8388608|LocationCount=5|X1=570|Y1=550|X2=660|Y2=550|X3=660|Y3=680|X4=600|Y4=680|X5=600|Y5=670
|RECORD=27|IndexInSheet=93|OwnerPartId=-1|LineWidth=1|Color=8388608|LocationCount=2|X1=700|Y1=280|X2=730|Y2=280
|RECORD=27|IndexInSheet=94|OwnerPartId=-1|LineWidth=1|Color=8388608|LocationCount=2|X1=840|Y1=280|X2=830|Y2=280
|RECORD=27|IndexInSheet=95|OwnerPartId=-1|LineWidth=1|Color=8388608|LocationCount=2|X1=680|Y1=480|X2=730|Y2=480
|RECORD=27|IndexInSheet=96|OwnerPartId=-1|LineWidth=1|Color=8388608|LocationCount=5|X1=530|Y1=600|X2=600|Y2=600|X3=820|Y3=600|X4=820|Y4=480|X5=800|Y5=480
|RECORD=27|IndexInSheet=97|OwnerPartId=-1|LineWidth=1|Color=8388608|LocationCount=2|X1=580|Y1=410|X2=730|Y2=410
|RECORD=27|IndexInSheet=98|OwnerPartId=-1|LineWidth=1|Color=8388608|LocationCount=2|X1=800|Y1=410|X2=870|Y2=410
|RECORD=27|IndexInSheet=99|OwnerPartId=-1|LineWidth=1|Color=8388608|LocationCount=2|X1=870|Y1=340|X2=800|Y2=340
|RECORD=27|IndexInSheet=100|OwnerPartId=-1|LineWidth=1|Color=8388608|LocationCount=4|X1=730|Y1=340|X2=610|Y2=340|X3=610|Y3=290|X4=490|Y4=290
|RECORD=27|IndexInSheet=101|OwnerPartId=-1|LineWidth=1|Color=8388608|LocationCount=2|X1=290|Y1=260|X2=290|Y2=290
|RECORD=27|IndexInSheet=102|OwnerPartId=-1|LineWidth=1|Color=8388608|LocationCount=2|X1=290|Y1=290|X2=310|Y2=290
|RECORD=27|IndexInSheet=103|OwnerPartId=-1|LineWidth=1|Color=8388608|LocationCount=2|X1=200|Y1=280|X2=200|Y2=270
|RECORD=27|IndexInSheet=104|OwnerPartId=-1|LineWidth=1|Color=8388608|LocationCount=3|X1=280|Y1=350|X2=280|Y2=360|X3=220|Y3=360
|RECORD=27|IndexInSheet=105|OwnerPartId=-1|LineWidth=1|Color=8388608|LocationCount=4|X1=400|Y1=360|X2=400|Y2=550|X3=460|Y3=550|X4=480|Y4=550
|RECORD=27|IndexInSheet=106|OwnerPartId=-1|LineWidth=1|Color=8388608|LocationCount=2|X1=400|Y1=330|X2=400|Y2=290
|RECORD=27|IndexInSheet=107|OwnerPartId=-1|LineWidth=1|Color=8388608|LocationCount=3|X1=200|Y1=290|X2=280|Y2=290|X3=290|Y3=290
|RECORD=27|IndexInSheet=108|OwnerPartId=-1|LineWidth=1|Color=8388608|LocationCount=2|X1=280|Y1=290|X2=280|Y2=330
|RECORD=27|IndexInSheet=109|OwnerPartId=-1|LineWidth=1|Color=8388608|LocationCount=2|X1=440|Y1=40|X2=390|Y2=40
|RECORD=27|IndexInSheet=110|OwnerPartId=-1|LineWidth=1|Color=8388608|LocationCount=2|X1=540|Y1=40|X2=460|Y2=40
|RECORD=27|IndexInSheet=111|OwnerPartId=-1|LineWidth=1|Color=8388608|LocationCount=3|X1=460|Y1=390|X2=460|Y2=400|X3=460|Y3=430
|RECORD=27|IndexInSheet=112|OwnerPartId=-1|LineWidth=1|Color=8388608|LocationCount=4|X1=500|Y1=420|X2=490|Y2=420|X3=490|Y3=290|X4=400|Y4=290
|RECORD=27|IndexInSheet=113|OwnerPartId=-1|LineWidth=1|Color=8388608|LocationCount=2|X1=500|Y1=400|X2=460|Y2=400
|RECORD=29|IndexInSheet=-1|OwnerPartId=-1|Location.X=200|Location.Y=270|Color=128
|RECORD=29|IndexInSheet=-1|OwnerPartId=-1|Location.X=280|Location.Y=290|Color=128
|RECORD=29|IndexInSheet=-1|OwnerPartId=-1|Location.X=290|Location.Y=290|Color=128
|RECORD=29|IndexInSheet=-1|OwnerPartId=-1|Location.X=400|Location.Y=290|Color=128
|RECORD=29|IndexInSheet=-1|OwnerPartId=-1|Location.X=460|Location.Y=400|Color=128
|RECORD=29|IndexInSheet=-1|OwnerPartId=-1|Location.X=460|Location.Y=550|Color=128
|RECORD=29|IndexInSheet=-1|OwnerPartId=-1|Location.X=490|Location.Y=290|Color=128
|RECORD=29|IndexInSheet=-1|OwnerPartId=-1|Location.X=540|Location.Y=480|Color=128
|RECORD=29|IndexInSheet=-1|OwnerPartId=-1|Location.X=600|Location.Y=600|Color=128
|RECORD=29|IndexInSheet=-1|OwnerPartId=-1|Location.X=660|Location.Y=680|Color=128
|RECORD=29|IndexInSheet=-1|OwnerPartId=-1|Location.X=700|Location.Y=280|Color=128